(kicad_sch (version 20230121) (generator eeschema)

  (paper "A3")

  (title_block
    (title "Kria K26 Devboard")
    (date "2024-03-26")
    (rev "1.2.5")
    (comment 1 "www.antmicro.com")
    (comment 2 "Antmicro Ltd.")
  )

  (junction (at 357.505 142.24) (diameter 0) (color 0 0 0 0)
  )
  (junction (at 364.49 154.94) (diameter 0) (color 0 0 0 0)
  )
  (junction (at 33.02 48.26) (diameter 0) (color 0 0 0 0)
  )
  (junction (at 341.63 91.44) (diameter 0) (color 0 0 0 0)
  )
  (junction (at 334.01 66.04) (diameter 0) (color 0 0 0 0)
  )
  (junction (at 115.57 144.78) (diameter 0) (color 0 0 0 0)
  )
  (junction (at 111.76 144.78) (diameter 0) (color 0 0 0 0)
  )
  (junction (at 334.01 41.91) (diameter 0) (color 0 0 0 0)
  )
  (junction (at 367.665 152.4) (diameter 0) (color 0 0 0 0)
  )
  (junction (at 292.735 137.16) (diameter 0) (color 0 0 0 0)
  )
  (junction (at 360.045 144.78) (diameter 0) (color 0 0 0 0)
  )
  (junction (at 311.15 110.49) (diameter 0) (color 0 0 0 0)
  )
  (junction (at 92.71 228.6) (diameter 0) (color 0 0 0 0)
  )
  (junction (at 175.895 120.65) (diameter 0) (color 0 0 0 0)
  )
  (junction (at 362.585 147.32) (diameter 0) (color 0 0 0 0)
  )
  (junction (at 198.12 48.26) (diameter 0) (color 0 0 0 0)
  )
  (junction (at 97.79 44.45) (diameter 0) (color 0 0 0 0)
  )
  (junction (at 176.53 55.88) (diameter 0) (color 0 0 0 0)
  )
  (junction (at 45.72 48.26) (diameter 0) (color 0 0 0 0)
  )
  (junction (at 226.06 110.49) (diameter 0) (color 0 0 0 0)
  )
  (junction (at 318.77 78.74) (diameter 0) (color 0 0 0 0)
  )
  (junction (at 72.39 143.51) (diameter 0) (color 0 0 0 0)
  )
  (junction (at 198.12 45.72) (diameter 0) (color 0 0 0 0)
  )
  (junction (at 236.855 60.96) (diameter 0) (color 0 0 0 0)
  )
  (junction (at 229.235 58.42) (diameter 0) (color 0 0 0 0)
  )
  (junction (at 365.125 149.86) (diameter 0) (color 0 0 0 0)
  )
  (junction (at 311.15 41.91) (diameter 0) (color 0 0 0 0)
  )
  (junction (at 197.485 118.11) (diameter 0) (color 0 0 0 0)
  )
  (junction (at 221.615 55.88) (diameter 0) (color 0 0 0 0)
  )
  (junction (at 77.47 143.51) (diameter 0) (color 0 0 0 0)
  )
  (junction (at 354.965 139.7) (diameter 0) (color 0 0 0 0)
  )
  (junction (at 213.995 53.34) (diameter 0) (color 0 0 0 0)
  )
  (junction (at 311.15 53.34) (diameter 0) (color 0 0 0 0)
  )

  (no_connect (at 293.37 125.73))
  (no_connect (at 373.38 134.62))
  (no_connect (at 303.53 125.73))
  (no_connect (at 196.215 113.03))

  (wire (pts (xy 45.72 48.26) (xy 48.895 48.26))
    (stroke (width 0) (type default))
  )
  (wire (pts (xy 352.425 147.32) (xy 362.585 147.32))
    (stroke (width 0) (type default))
  )
  (wire (pts (xy 111.76 141.605) (xy 111.76 144.78))
    (stroke (width 0) (type default))
  )
  (wire (pts (xy 303.53 91.44) (xy 341.63 91.44))
    (stroke (width 0) (type default))
  )
  (wire (pts (xy 284.48 60.96) (xy 284.48 91.44))
    (stroke (width 0) (type default))
  )
  (wire (pts (xy 175.895 120.65) (xy 175.895 123.19))
    (stroke (width 0) (type default))
  )
  (wire (pts (xy 200.025 259.08) (xy 209.55 259.08))
    (stroke (width 0) (type default))
  )
  (wire (pts (xy 357.505 142.24) (xy 373.38 142.24))
    (stroke (width 0) (type default))
  )
  (wire (pts (xy 236.855 60.96) (xy 284.48 60.96))
    (stroke (width 0) (type default))
  )
  (wire (pts (xy 341.63 49.53) (xy 341.63 91.44))
    (stroke (width 0) (type default))
  )
  (wire (pts (xy 198.12 48.26) (xy 198.12 50.8))
    (stroke (width 0) (type default))
  )
  (wire (pts (xy 236.855 62.865) (xy 236.855 60.96))
    (stroke (width 0) (type default))
  )
  (wire (pts (xy 334.01 66.04) (xy 334.01 49.53))
    (stroke (width 0) (type default))
  )
  (wire (pts (xy 354.965 133.985) (xy 354.965 139.7))
    (stroke (width 0) (type default))
  )
  (wire (pts (xy 197.485 118.11) (xy 196.215 118.11))
    (stroke (width 0) (type default))
  )
  (wire (pts (xy 311.15 44.45) (xy 311.15 41.91))
    (stroke (width 0) (type default))
  )
  (wire (pts (xy 196.85 55.88) (xy 221.615 55.88))
    (stroke (width 0) (type default))
  )
  (wire (pts (xy 178.435 120.65) (xy 175.895 120.65))
    (stroke (width 0) (type default))
  )
  (wire (pts (xy 33.02 48.26) (xy 34.29 48.26))
    (stroke (width 0) (type default))
  )
  (wire (pts (xy 198.12 45.72) (xy 208.915 45.72))
    (stroke (width 0) (type default))
  )
  (polyline (pts (xy 270.51 12.7) (xy 270.51 283.21))
    (stroke (width 0) (type default))
  )

  (wire (pts (xy 196.85 58.42) (xy 229.235 58.42))
    (stroke (width 0) (type default))
  )
  (wire (pts (xy 352.425 137.16) (xy 373.38 137.16))
    (stroke (width 0) (type default))
  )
  (wire (pts (xy 334.01 41.91) (xy 341.63 41.91))
    (stroke (width 0) (type default))
  )
  (wire (pts (xy 352.425 149.86) (xy 365.125 149.86))
    (stroke (width 0) (type default))
  )
  (wire (pts (xy 292.735 137.16) (xy 306.07 137.16))
    (stroke (width 0) (type default))
  )
  (wire (pts (xy 92.71 228.6) (xy 101.854 228.6))
    (stroke (width 0) (type default))
  )
  (wire (pts (xy 200.66 48.26) (xy 198.12 48.26))
    (stroke (width 0) (type default))
  )
  (wire (pts (xy 199.39 200.66) (xy 203.2 200.66))
    (stroke (width 0) (type default))
  )
  (wire (pts (xy 191.77 204.47) (xy 203.2 204.47))
    (stroke (width 0) (type default))
  )
  (wire (pts (xy 56.515 48.26) (xy 70.485 48.26))
    (stroke (width 0) (type default))
  )
  (wire (pts (xy 97.79 41.91) (xy 97.79 44.45))
    (stroke (width 0) (type default))
  )
  (wire (pts (xy 360.045 144.78) (xy 373.38 144.78))
    (stroke (width 0) (type default))
  )
  (wire (pts (xy 175.895 113.03) (xy 178.435 113.03))
    (stroke (width 0) (type default))
  )
  (wire (pts (xy 364.49 154.94) (xy 364.49 158.115))
    (stroke (width 0) (type default))
  )
  (wire (pts (xy 364.49 154.94) (xy 373.38 154.94))
    (stroke (width 0) (type default))
  )
  (wire (pts (xy 198.755 106.68) (xy 196.215 106.68))
    (stroke (width 0) (type default))
  )
  (wire (pts (xy 293.37 91.44) (xy 284.48 91.44))
    (stroke (width 0) (type default))
  )
  (wire (pts (xy 362.585 133.985) (xy 362.585 147.32))
    (stroke (width 0) (type default))
  )
  (wire (pts (xy 196.85 50.8) (xy 198.12 50.8))
    (stroke (width 0) (type default))
  )
  (wire (pts (xy 176.53 55.88) (xy 175.26 55.88))
    (stroke (width 0) (type default))
  )
  (wire (pts (xy 72.39 143.51) (xy 72.39 140.335))
    (stroke (width 0) (type default))
  )
  (wire (pts (xy 159.385 128.27) (xy 160.655 128.27))
    (stroke (width 0) (type default))
  )
  (wire (pts (xy 311.15 98.425) (xy 311.15 101.6))
    (stroke (width 0) (type default))
  )
  (wire (pts (xy 331.47 41.91) (xy 334.01 41.91))
    (stroke (width 0) (type default))
  )
  (wire (pts (xy 92.71 226.06) (xy 92.71 228.6))
    (stroke (width 0) (type default))
  )
  (wire (pts (xy 304.165 142.24) (xy 304.165 146.685))
    (stroke (width 0) (type default))
  )
  (wire (pts (xy 352.425 142.24) (xy 357.505 142.24))
    (stroke (width 0) (type default))
  )
  (wire (pts (xy 360.045 144.78) (xy 352.425 144.78))
    (stroke (width 0) (type default))
  )
  (wire (pts (xy 365.125 133.985) (xy 365.125 149.86))
    (stroke (width 0) (type default))
  )
  (wire (pts (xy 308.61 41.91) (xy 311.15 41.91))
    (stroke (width 0) (type default))
  )
  (wire (pts (xy 33.02 45.72) (xy 33.02 48.26))
    (stroke (width 0) (type default))
  )
  (wire (pts (xy 286.385 58.42) (xy 286.385 78.74))
    (stroke (width 0) (type default))
  )
  (wire (pts (xy 115.57 144.78) (xy 111.76 144.78))
    (stroke (width 0) (type default))
  )
  (wire (pts (xy 311.15 53.34) (xy 311.15 49.53))
    (stroke (width 0) (type default))
  )
  (wire (pts (xy 318.77 49.53) (xy 318.77 78.74))
    (stroke (width 0) (type default))
  )
  (wire (pts (xy 31.75 48.26) (xy 31.75 49.53))
    (stroke (width 0) (type default))
  )
  (wire (pts (xy 77.47 143.51) (xy 81.28 143.51))
    (stroke (width 0) (type default))
  )
  (wire (pts (xy 221.615 55.88) (xy 221.615 62.865))
    (stroke (width 0) (type default))
  )
  (wire (pts (xy 185.42 259.08) (xy 194.945 259.08))
    (stroke (width 0) (type default))
  )
  (polyline (pts (xy 134.62 123.825) (xy 50.8 123.825))
    (stroke (width 0) (type default))
  )
  (polyline (pts (xy 13.97 171.45) (xy 402.59 171.45))
    (stroke (width 0) (type default))
  )

  (wire (pts (xy 292.735 137.16) (xy 292.735 139.065))
    (stroke (width 0) (type default))
  )
  (wire (pts (xy 361.95 154.94) (xy 364.49 154.94))
    (stroke (width 0) (type default))
  )
  (wire (pts (xy 45.72 48.26) (xy 44.45 48.26))
    (stroke (width 0) (type default))
  )
  (wire (pts (xy 303.53 53.34) (xy 311.15 53.34))
    (stroke (width 0) (type default))
  )
  (polyline (pts (xy 50.8 123.825) (xy 50.8 171.45))
    (stroke (width 0) (type default))
  )

  (wire (pts (xy 149.86 38.1) (xy 151.765 38.1))
    (stroke (width 0) (type default))
  )
  (wire (pts (xy 352.425 152.4) (xy 367.665 152.4))
    (stroke (width 0) (type default))
  )
  (wire (pts (xy 160.655 113.03) (xy 159.385 113.03))
    (stroke (width 0) (type default))
  )
  (wire (pts (xy 172.72 193.675) (xy 172.72 195.58))
    (stroke (width 0) (type default))
  )
  (wire (pts (xy 311.15 53.34) (xy 346.71 53.34))
    (stroke (width 0) (type default))
  )
  (wire (pts (xy 226.06 110.49) (xy 293.37 110.49))
    (stroke (width 0) (type default))
  )
  (wire (pts (xy 304.165 142.24) (xy 306.07 142.24))
    (stroke (width 0) (type default))
  )
  (wire (pts (xy 118.872 144.78) (xy 115.57 144.78))
    (stroke (width 0) (type default))
  )
  (polyline (pts (xy 134.62 12.7) (xy 134.62 284.48))
    (stroke (width 0) (type default))
  )

  (wire (pts (xy 108.585 133.985) (xy 111.76 133.985))
    (stroke (width 0) (type default))
  )
  (wire (pts (xy 357.505 133.985) (xy 357.505 142.24))
    (stroke (width 0) (type default))
  )
  (wire (pts (xy 106.68 52.705) (xy 108.585 52.705))
    (stroke (width 0) (type default))
  )
  (wire (pts (xy 198.12 43.18) (xy 196.85 43.18))
    (stroke (width 0) (type default))
  )
  (wire (pts (xy 196.85 60.96) (xy 236.855 60.96))
    (stroke (width 0) (type default))
  )
  (wire (pts (xy 334.01 44.45) (xy 334.01 41.91))
    (stroke (width 0) (type default))
  )
  (wire (pts (xy 77.47 142.24) (xy 77.47 143.51))
    (stroke (width 0) (type default))
  )
  (wire (pts (xy 108.585 52.705) (xy 108.585 54.61))
    (stroke (width 0) (type default))
  )
  (wire (pts (xy 33.02 48.26) (xy 31.75 48.26))
    (stroke (width 0) (type default))
  )
  (wire (pts (xy 87.63 242.57) (xy 87.63 236.22))
    (stroke (width 0) (type default))
  )
  (wire (pts (xy 53.848 151.13) (xy 64.77 151.13))
    (stroke (width 0) (type default))
  )
  (wire (pts (xy 196.85 40.64) (xy 200.025 40.64))
    (stroke (width 0) (type default))
  )
  (wire (pts (xy 222.885 204.47) (xy 220.98 204.47))
    (stroke (width 0) (type default))
  )
  (wire (pts (xy 196.85 45.72) (xy 198.12 45.72))
    (stroke (width 0) (type default))
  )
  (wire (pts (xy 360.045 133.985) (xy 360.045 144.78))
    (stroke (width 0) (type default))
  )
  (wire (pts (xy 311.15 41.91) (xy 318.77 41.91))
    (stroke (width 0) (type default))
  )
  (wire (pts (xy 367.665 133.985) (xy 367.665 152.4))
    (stroke (width 0) (type default))
  )
  (wire (pts (xy 198.12 43.18) (xy 198.12 45.72))
    (stroke (width 0) (type default))
  )
  (wire (pts (xy 226.06 115.57) (xy 226.06 110.49))
    (stroke (width 0) (type default))
  )
  (wire (pts (xy 311.15 110.49) (xy 311.15 106.68))
    (stroke (width 0) (type default))
  )
  (wire (pts (xy 151.765 52.705) (xy 151.765 54.61))
    (stroke (width 0) (type default))
  )
  (wire (pts (xy 177.8 53.34) (xy 175.26 53.34))
    (stroke (width 0) (type default))
  )
  (wire (pts (xy 196.215 120.65) (xy 208.28 120.65))
    (stroke (width 0) (type default))
  )
  (wire (pts (xy 286.385 58.42) (xy 229.235 58.42))
    (stroke (width 0) (type default))
  )
  (wire (pts (xy 213.995 53.34) (xy 293.37 53.34))
    (stroke (width 0) (type default))
  )
  (wire (pts (xy 175.895 113.03) (xy 175.895 120.65))
    (stroke (width 0) (type default))
  )
  (wire (pts (xy 367.665 152.4) (xy 373.38 152.4))
    (stroke (width 0) (type default))
  )
  (wire (pts (xy 44.45 45.72) (xy 45.72 45.72))
    (stroke (width 0) (type default))
  )
  (wire (pts (xy 176.53 55.88) (xy 176.53 58.42))
    (stroke (width 0) (type default))
  )
  (wire (pts (xy 303.53 66.04) (xy 334.01 66.04))
    (stroke (width 0) (type default))
  )
  (wire (pts (xy 85.725 236.22) (xy 87.63 236.22))
    (stroke (width 0) (type default))
  )
  (wire (pts (xy 318.77 41.91) (xy 318.77 44.45))
    (stroke (width 0) (type default))
  )
  (wire (pts (xy 175.895 106.68) (xy 178.435 106.68))
    (stroke (width 0) (type default))
  )
  (wire (pts (xy 221.615 55.88) (xy 288.29 55.88))
    (stroke (width 0) (type default))
  )
  (wire (pts (xy 290.195 137.16) (xy 292.735 137.16))
    (stroke (width 0) (type default))
  )
  (wire (pts (xy 175.895 43.18) (xy 175.895 45.085))
    (stroke (width 0) (type default))
  )
  (wire (pts (xy 89.535 44.45) (xy 97.79 44.45))
    (stroke (width 0) (type default))
  )
  (wire (pts (xy 198.12 48.26) (xy 196.85 48.26))
    (stroke (width 0) (type default))
  )
  (wire (pts (xy 200.66 49.53) (xy 200.66 48.26))
    (stroke (width 0) (type default))
  )
  (wire (pts (xy 109.855 235.585) (xy 112.395 235.585))
    (stroke (width 0) (type default))
  )
  (wire (pts (xy 59.69 228.6) (xy 66.675 228.6))
    (stroke (width 0) (type default))
  )
  (wire (pts (xy 293.37 66.04) (xy 288.29 66.04))
    (stroke (width 0) (type default))
  )
  (wire (pts (xy 362.585 147.32) (xy 373.38 147.32))
    (stroke (width 0) (type default))
  )
  (wire (pts (xy 160.655 114.935) (xy 160.655 113.03))
    (stroke (width 0) (type default))
  )
  (wire (pts (xy 95.504 152.4) (xy 104.14 152.4))
    (stroke (width 0) (type default))
  )
  (wire (pts (xy 90.805 52.07) (xy 89.535 52.07))
    (stroke (width 0) (type default))
  )
  (wire (pts (xy 177.8 60.96) (xy 176.53 60.96))
    (stroke (width 0) (type default))
  )
  (polyline (pts (xy 270.51 222.25) (xy 134.62 222.25))
    (stroke (width 0) (type default))
  )

  (wire (pts (xy 197.485 118.11) (xy 197.485 122.555))
    (stroke (width 0) (type default))
  )
  (wire (pts (xy 170.18 193.675) (xy 172.72 193.675))
    (stroke (width 0) (type default))
  )
  (wire (pts (xy 151.765 38.1) (xy 151.765 40.005))
    (stroke (width 0) (type default))
  )
  (wire (pts (xy 34.29 45.72) (xy 33.02 45.72))
    (stroke (width 0) (type default))
  )
  (wire (pts (xy 173.99 40.64) (xy 177.8 40.64))
    (stroke (width 0) (type default))
  )
  (wire (pts (xy 112.395 235.585) (xy 112.395 237.49))
    (stroke (width 0) (type default))
  )
  (wire (pts (xy 58.42 236.22) (xy 66.675 236.22))
    (stroke (width 0) (type default))
  )
  (wire (pts (xy 197.485 115.57) (xy 197.485 118.11))
    (stroke (width 0) (type default))
  )
  (wire (pts (xy 177.8 43.18) (xy 175.895 43.18))
    (stroke (width 0) (type default))
  )
  (wire (pts (xy 229.235 62.865) (xy 229.235 58.42))
    (stroke (width 0) (type default))
  )
  (wire (pts (xy 318.77 78.74) (xy 346.71 78.74))
    (stroke (width 0) (type default))
  )
  (wire (pts (xy 67.31 52.07) (xy 70.485 52.07))
    (stroke (width 0) (type default))
  )
  (polyline (pts (xy 92.71 123.825) (xy 92.71 171.45))
    (stroke (width 0) (type default))
  )

  (wire (pts (xy 72.39 146.05) (xy 72.39 143.51))
    (stroke (width 0) (type default))
  )
  (wire (pts (xy 196.215 110.49) (xy 226.06 110.49))
    (stroke (width 0) (type default))
  )
  (wire (pts (xy 67.31 52.705) (xy 67.31 52.07))
    (stroke (width 0) (type default))
  )
  (wire (pts (xy 286.385 78.74) (xy 293.37 78.74))
    (stroke (width 0) (type default))
  )
  (wire (pts (xy 177.8 55.88) (xy 176.53 55.88))
    (stroke (width 0) (type default))
  )
  (wire (pts (xy 53.975 232.41) (xy 66.675 232.41))
    (stroke (width 0) (type default))
  )
  (wire (pts (xy 308.61 98.425) (xy 311.15 98.425))
    (stroke (width 0) (type default))
  )
  (wire (pts (xy 111.76 136.525) (xy 111.76 133.985))
    (stroke (width 0) (type default))
  )
  (wire (pts (xy 67.945 44.45) (xy 70.485 44.45))
    (stroke (width 0) (type default))
  )
  (wire (pts (xy 72.39 135.255) (xy 72.39 132.715))
    (stroke (width 0) (type default))
  )
  (wire (pts (xy 85.725 228.6) (xy 92.71 228.6))
    (stroke (width 0) (type default))
  )
  (wire (pts (xy 72.39 143.51) (xy 77.47 143.51))
    (stroke (width 0) (type default))
  )
  (wire (pts (xy 303.53 78.74) (xy 318.77 78.74))
    (stroke (width 0) (type default))
  )
  (wire (pts (xy 58.42 237.49) (xy 58.42 236.22))
    (stroke (width 0) (type default))
  )
  (wire (pts (xy 365.125 149.86) (xy 373.38 149.86))
    (stroke (width 0) (type default))
  )
  (wire (pts (xy 341.63 44.45) (xy 341.63 41.91))
    (stroke (width 0) (type default))
  )
  (wire (pts (xy 69.215 132.715) (xy 72.39 132.715))
    (stroke (width 0) (type default))
  )
  (wire (pts (xy 177.165 110.49) (xy 178.435 110.49))
    (stroke (width 0) (type default))
  )
  (wire (pts (xy 354.965 139.7) (xy 373.38 139.7))
    (stroke (width 0) (type default))
  )
  (wire (pts (xy 334.01 66.04) (xy 346.71 66.04))
    (stroke (width 0) (type default))
  )
  (wire (pts (xy 160.655 128.27) (xy 160.655 130.175))
    (stroke (width 0) (type default))
  )
  (wire (pts (xy 115.57 143.51) (xy 115.57 144.78))
    (stroke (width 0) (type default))
  )
  (wire (pts (xy 177.8 58.42) (xy 176.53 58.42))
    (stroke (width 0) (type default))
  )
  (wire (pts (xy 303.53 110.49) (xy 311.15 110.49))
    (stroke (width 0) (type default))
  )
  (wire (pts (xy 45.72 48.26) (xy 45.72 232.41))
    (stroke (width 0) (type default))
  )
  (wire (pts (xy 90.805 57.785) (xy 90.805 52.07))
    (stroke (width 0) (type default))
  )
  (wire (pts (xy 196.85 53.34) (xy 213.995 53.34))
    (stroke (width 0) (type default))
  )
  (wire (pts (xy 149.86 52.705) (xy 151.765 52.705))
    (stroke (width 0) (type default))
  )
  (wire (pts (xy 288.29 55.88) (xy 288.29 66.04))
    (stroke (width 0) (type default))
  )
  (wire (pts (xy 45.72 45.72) (xy 45.72 48.26))
    (stroke (width 0) (type default))
  )
  (wire (pts (xy 311.15 110.49) (xy 346.71 110.49))
    (stroke (width 0) (type default))
  )
  (wire (pts (xy 111.76 147.32) (xy 111.76 144.78))
    (stroke (width 0) (type default))
  )
  (wire (pts (xy 200.025 196.85) (xy 203.2 196.85))
    (stroke (width 0) (type default))
  )
  (wire (pts (xy 222.885 206.375) (xy 222.885 204.47))
    (stroke (width 0) (type default))
  )
  (wire (pts (xy 45.72 232.41) (xy 46.355 232.41))
    (stroke (width 0) (type default))
  )
  (wire (pts (xy 341.63 91.44) (xy 346.71 91.44))
    (stroke (width 0) (type default))
  )
  (wire (pts (xy 220.98 200.66) (xy 223.52 200.66))
    (stroke (width 0) (type default))
  )
  (wire (pts (xy 354.965 139.7) (xy 352.425 139.7))
    (stroke (width 0) (type default))
  )
  (wire (pts (xy 108.204 44.45) (xy 97.79 44.45))
    (stroke (width 0) (type default))
  )
  (wire (pts (xy 213.995 62.865) (xy 213.995 53.34))
    (stroke (width 0) (type default))
  )
  (wire (pts (xy 196.215 115.57) (xy 197.485 115.57))
    (stroke (width 0) (type default))
  )

  (text "Deassert RESET 25ms after PS_3V3 PGOOD" (at 54.61 71.12 0)
    (effects (font (size 1.27 1.27)) (justify left bottom))
  )
  (text "B -> A" (at 183.515 66.04 0)
    (effects (font (size 1.27 1.27)) (justify left bottom))
  )
  (text "Optional PL bypass \n(when using DNP other PL reset circuitry)"
    (at 158.75 236.22 0)
    (effects (font (size 2.54 2.54)) (justify left bottom))
  )
  (text "Manual reset\nwith debounce" (at 41.91 66.04 90)
    (effects (font (size 1.27 1.27)) (justify left bottom))
  )
  (text "Logic level conversion enabled by voltage supervisor"
    (at 153.67 25.4 0)
    (effects (font (size 2.54 2.54)) (justify left bottom))
  )
  (text "Clock enable" (at 95.25 127 0)
    (effects (font (size 1.27 1.27)) (justify left bottom))
  )
  (text "PS voltage supervisor (3V0 threshold) with manual reset"
    (at 15.24 25.4 0)
    (effects (font (size 2.54 2.54)) (justify left bottom))
  )
  (text "Reset debug connector" (at 341.63 123.19 0)
    (effects (font (size 2.54 2.54)) (justify left bottom))
  )
  (text "PS domain" (at 13.97 17.78 0)
    (effects (font (size 2.54 2.54) (thickness 0.508) bold) (justify left bottom))
  )
  (text "PL domain" (at 12.7 176.53 0)
    (effects (font (size 2.54 2.54) (thickness 0.508) bold) (justify left bottom))
  )
  (text "Default reset" (at 228.6 119.38 0)
    (effects (font (size 1.27 1.27)) (justify left bottom))
  )
  (text "OD reset buffer" (at 295.91 25.4 0)
    (effects (font (size 2.54 2.54)) (justify left bottom))
  )
  (text "SOM reset\n" (at 52.07 127 0)
    (effects (font (size 1.27 1.27)) (justify left bottom))
  )
  (text "PL voltage supervisor (3V0 threshold) \nwith manual reset"
    (at 54.61 182.88 0)
    (effects (font (size 2.54 2.54)) (justify left bottom))
  )
  (text "B -> A" (at 183.515 123.19 0)
    (effects (font (size 1.27 1.27)) (justify left bottom))
  )
  (text "Xilinx reference" (at 274.32 179.07 0)
    (effects (font (size 2.54 2.54) (thickness 0.508) bold) (justify left bottom))
  )
  (text "Resert OE controlled by voltage supervisor" (at 158.75 179.07 0)
    (effects (font (size 2.54 2.54)) (justify left bottom))
  )
  (text "B -> A" (at 183.515 68.58 0)
    (effects (font (size 1.27 1.27)) (justify left bottom))
  )
  (text "Default reset" (at 240.665 72.39 0)
    (effects (font (size 1.27 1.27)) (justify left bottom))
  )
  (text "Deassert RESET 25ms after PS_3V3 PGOOD" (at 55.245 253.365 0)
    (effects (font (size 1.27 1.27)) (justify left bottom))
  )

  (label "PL_RST" (at 101.854 228.6 180) (fields_autoplaced)
    (effects (font (size 1.27 1.27)) (justify right bottom))
  )
  (label "PS_RST" (at 208.28 120.65 180) (fields_autoplaced)
    (effects (font (size 1.27 1.27)) (justify right bottom))
  )
  (label "PS_RST" (at 208.915 45.72 180) (fields_autoplaced)
    (effects (font (size 1.27 1.27)) (justify right bottom))
  )
  (label "PS_RST" (at 108.204 44.45 180) (fields_autoplaced)
    (effects (font (size 1.27 1.27)) (justify right bottom))
  )
  (label "PS_RST" (at 53.848 151.13 0) (fields_autoplaced)
    (effects (font (size 1.27 1.27)) (justify left bottom))
  )
  (label "PS_RST" (at 95.504 152.4 0) (fields_autoplaced)
    (effects (font (size 1.27 1.27)) (justify left bottom))
  )
  (label "PL_RST" (at 191.77 204.47 0) (fields_autoplaced)
    (effects (font (size 1.27 1.27)) (justify left bottom))
  )

  (global_label "PS_1V8" (shape input) (at 175.895 106.68 180) (fields_autoplaced)
    (effects (font (size 1.27 1.27)) (justify right))
    (property "Intersheetrefs" "${INTERSHEET_REFS}" (at 6.985 -13.97 0)
      (effects (font (size 1.27 1.27)) hide)
    )
  )
  (global_label "PS_1V8" (shape input) (at 173.99 40.64 180) (fields_autoplaced)
    (effects (font (size 1.27 1.27)) (justify right))
    (property "Intersheetrefs" "${INTERSHEET_REFS}" (at 132.08 226.06 0)
      (effects (font (size 1.27 1.27)) hide)
    )
  )
  (global_label "PS_3V3" (shape input) (at 308.61 41.91 180) (fields_autoplaced)
    (effects (font (size 1.27 1.27)) (justify right))
    (property "Intersheetrefs" "${INTERSHEET_REFS}" (at 266.7 353.06 0)
      (effects (font (size 1.27 1.27)) hide)
    )
  )
  (global_label "PS_1V8" (shape input) (at 331.47 41.91 180) (fields_autoplaced)
    (effects (font (size 1.27 1.27)) (justify right))
    (property "Intersheetrefs" "${INTERSHEET_REFS}" (at 289.56 360.68 0)
      (effects (font (size 1.27 1.27)) hide)
    )
  )
  (global_label "PS_1V8" (shape input) (at 149.86 38.1 180) (fields_autoplaced)
    (effects (font (size 1.27 1.27)) (justify right))
    (property "Intersheetrefs" "${INTERSHEET_REFS}" (at 64.77 204.47 0)
      (effects (font (size 1.27 1.27)) hide)
    )
  )
  (global_label "PL_3V3" (shape input) (at 109.855 235.585 180) (fields_autoplaced)
    (effects (font (size 1.27 1.27)) (justify right))
    (property "Intersheetrefs" "${INTERSHEET_REFS}" (at -117.475 347.345 0)
      (effects (font (size 1.27 1.27)) hide)
    )
  )
  (global_label "PS_3V3" (shape input) (at 198.755 106.68 0) (fields_autoplaced)
    (effects (font (size 1.27 1.27)) (justify left))
    (property "Intersheetrefs" "${INTERSHEET_REFS}" (at -9.525 -13.97 0)
      (effects (font (size 1.27 1.27)) hide)
    )
  )
  (global_label "PS_3V3" (shape input) (at 149.86 52.705 180) (fields_autoplaced)
    (effects (font (size 1.27 1.27)) (justify right))
    (property "Intersheetrefs" "${INTERSHEET_REFS}" (at 64.77 230.505 0)
      (effects (font (size 1.27 1.27)) hide)
    )
  )
  (global_label "PS_1V8" (shape input) (at 69.215 132.715 180) (fields_autoplaced)
    (effects (font (size 1.27 1.27)) (justify right))
    (property "Intersheetrefs" "${INTERSHEET_REFS}" (at -56.515 205.105 0)
      (effects (font (size 1.27 1.27)) hide)
    )
  )
  (global_label "PS_3V3" (shape input) (at 290.195 137.16 180) (fields_autoplaced)
    (effects (font (size 1.27 1.27)) (justify right))
    (property "Intersheetrefs" "${INTERSHEET_REFS}" (at 4.445 2.54 0)
      (effects (font (size 1.27 1.27)) hide)
    )
  )
  (global_label "PL_3V3" (shape input) (at 170.18 193.675 180) (fields_autoplaced)
    (effects (font (size 1.27 1.27)) (justify right))
    (property "Intersheetrefs" "${INTERSHEET_REFS}" (at -24.13 366.395 0)
      (effects (font (size 1.27 1.27)) hide)
    )
  )
  (global_label "PS_3V3" (shape input) (at 67.945 44.45 180) (fields_autoplaced)
    (effects (font (size 1.27 1.27)) (justify right))
    (property "Intersheetrefs" "${INTERSHEET_REFS}" (at 8.255 0 0)
      (effects (font (size 1.27 1.27)) hide)
    )
  )
  (global_label "PS_3V3" (shape input) (at 200.025 40.64 0) (fields_autoplaced)
    (effects (font (size 1.27 1.27)) (justify left))
    (property "Intersheetrefs" "${INTERSHEET_REFS}" (at 241.935 -149.86 0)
      (effects (font (size 1.27 1.27)) hide)
    )
  )
  (global_label "PL_3V3" (shape input) (at 200.025 196.85 180) (fields_autoplaced)
    (effects (font (size 1.27 1.27)) (justify right))
    (property "Intersheetrefs" "${INTERSHEET_REFS}" (at 5.715 407.67 0)
      (effects (font (size 1.27 1.27)) hide)
    )
  )
  (global_label "PS_3V3" (shape input) (at 308.61 98.425 180) (fields_autoplaced)
    (effects (font (size 1.27 1.27)) (justify right))
    (property "Intersheetrefs" "${INTERSHEET_REFS}" (at 198.12 409.575 0)
      (effects (font (size 1.27 1.27)) hide)
    )
  )
  (global_label "PS_3V3" (shape input) (at 108.585 133.985 180) (fields_autoplaced)
    (effects (font (size 1.27 1.27)) (justify right))
    (property "Intersheetrefs" "${INTERSHEET_REFS}" (at -17.145 245.745 0)
      (effects (font (size 1.27 1.27)) hide)
    )
  )
  (global_label "PS_3V3" (shape input) (at 106.68 52.705 180) (fields_autoplaced)
    (effects (font (size 1.27 1.27)) (justify right))
    (property "Intersheetrefs" "${INTERSHEET_REFS}" (at 63.5 158.115 0)
      (effects (font (size 1.27 1.27)) hide)
    )
  )
  (global_label "PL_3V3" (shape input) (at 59.69 228.6 180) (fields_autoplaced)
    (effects (font (size 1.27 1.27)) (justify right))
    (property "Intersheetrefs" "${INTERSHEET_REFS}" (at 50.5857 228.6 0)
      (effects (font (size 1.27 1.27)) (justify right) hide)
    )
  )
  (global_label "PS_3V3" (shape input) (at 159.385 128.27 180) (fields_autoplaced)
    (effects (font (size 1.27 1.27)) (justify right))
    (property "Intersheetrefs" "${INTERSHEET_REFS}" (at 59.055 337.82 0)
      (effects (font (size 1.27 1.27)) hide)
    )
  )
  (global_label "PS_1V8" (shape input) (at 159.385 113.03 180) (fields_autoplaced)
    (effects (font (size 1.27 1.27)) (justify right))
    (property "Intersheetrefs" "${INTERSHEET_REFS}" (at 59.055 311.15 0)
      (effects (font (size 1.27 1.27)) hide)
    )
  )

  (hierarchical_label "HDA02" (shape input) (at 199.39 200.66 180) (fields_autoplaced)
    (effects (font (size 1.27 1.27)) (justify right))
  )
  (hierarchical_label "PS_CLOCK_EN" (shape input) (at 118.872 144.78 0) (fields_autoplaced)
    (effects (font (size 1.27 1.27)) (justify left))
  )
  (hierarchical_label "~{USB_PHY_RESET}" (shape input) (at 352.425 142.24 180) (fields_autoplaced)
    (effects (font (size 1.27 1.27)) (justify right))
  )
  (hierarchical_label "~{USB_HUB_RESET}" (shape input) (at 352.425 144.78 180) (fields_autoplaced)
    (effects (font (size 1.27 1.27)) (justify right))
  )
  (hierarchical_label "MIO43" (shape input) (at 175.26 53.34 180) (fields_autoplaced)
    (effects (font (size 1.27 1.27)) (justify right))
  )
  (hierarchical_label "~{USB_PHY_RESET}" (shape input) (at 346.71 66.04 0) (fields_autoplaced)
    (effects (font (size 1.27 1.27)) (justify left))
  )
  (hierarchical_label "MIO44" (shape input) (at 175.26 55.88 180) (fields_autoplaced)
    (effects (font (size 1.27 1.27)) (justify right))
  )
  (hierarchical_label "~{USB_HUB_RESET}" (shape input) (at 346.71 78.74 0) (fields_autoplaced)
    (effects (font (size 1.27 1.27)) (justify left))
  )
  (hierarchical_label "~{ETH_RESET}" (shape input) (at 346.71 91.44 0) (fields_autoplaced)
    (effects (font (size 1.27 1.27)) (justify left))
  )
  (hierarchical_label "~{SD_CARD_RESET}" (shape input) (at 352.425 139.7 180) (fields_autoplaced)
    (effects (font (size 1.27 1.27)) (justify right))
  )
  (hierarchical_label "CAM_RST" (shape input) (at 209.55 259.08 0) (fields_autoplaced)
    (effects (font (size 1.27 1.27)) (justify left))
  )
  (hierarchical_label "~{SD_CARD_RESET}" (shape input) (at 346.71 53.34 0) (fields_autoplaced)
    (effects (font (size 1.27 1.27)) (justify left))
  )
  (hierarchical_label "MIO38" (shape input) (at 176.53 60.96 180) (fields_autoplaced)
    (effects (font (size 1.27 1.27)) (justify right))
  )
  (hierarchical_label "CAM_RST" (shape input) (at 223.52 200.66 0) (fields_autoplaced)
    (effects (font (size 1.27 1.27)) (justify left))
  )
  (hierarchical_label "~{M2_PERST}" (shape input) (at 346.71 110.49 0) (fields_autoplaced)
    (effects (font (size 1.27 1.27)) (justify left))
  )
  (hierarchical_label "MIO41" (shape input) (at 177.165 110.49 180) (fields_autoplaced)
    (effects (font (size 1.27 1.27)) (justify right))
  )
  (hierarchical_label "HDA02" (shape input) (at 185.42 259.08 180) (fields_autoplaced)
    (effects (font (size 1.27 1.27)) (justify right))
  )
  (hierarchical_label "~{PS_POR}" (shape input) (at 352.425 137.16 180) (fields_autoplaced)
    (effects (font (size 1.27 1.27)) (justify right))
  )
  (hierarchical_label "~{ETH_RESET}" (shape input) (at 352.425 147.32 180) (fields_autoplaced)
    (effects (font (size 1.27 1.27)) (justify right))
  )
  (hierarchical_label "CAM_RST" (shape input) (at 352.425 149.86 180) (fields_autoplaced)
    (effects (font (size 1.27 1.27)) (justify right))
  )
  (hierarchical_label "~{M2_PERST}" (shape input) (at 352.425 152.4 180) (fields_autoplaced)
    (effects (font (size 1.27 1.27)) (justify right))
  )
  (hierarchical_label "~{PS_POR}" (shape input) (at 81.28 143.51 0) (fields_autoplaced)
    (effects (font (size 1.27 1.27)) (justify left))
  )

  (symbol (lib_id "kria-k26-devboard:74LCX07_QFN") (at 293.37 110.49 0) (unit 1)
    (in_bom yes) (on_board yes) (dnp no) (fields_autoplaced)
    (property "Reference" "U36" (at 298.45 102.87 0)
      (effects (font (size 1.27 1.27)))
    )
    (property "Value" "74LCX07_QFN" (at 298.45 118.11 0)
      (effects (font (size 1.27 1.27) (thickness 0.15)) (justify left bottom))
    )
    (property "Footprint" "kria-k26-devboard-footprints:QFN-14-1EP_2.5x3mm_EP1.15x1.65mm_ONSemi_MLP14A" (at 295.91 119.38 0)
      (effects (font (size 1.27 1.27) (thickness 0.15)) (justify left bottom) hide)
    )
    (property "Datasheet" "https://www.mouser.com/datasheet/2/308/74LCX07_D-2309542.pdf" (at 293.37 110.49 0)
      (effects (font (size 1.27 1.27) (thickness 0.15)) (justify left bottom) hide)
    )
    (property "Manufacturer" "ON Semiconductor" (at 284.48 114.3 0)
      (effects (font (size 1.27 1.27) (thickness 0.15)) (justify left bottom) hide)
    )
    (property "MPN" "74LCX07BQX" (at 298.45 105.41 0)
      (effects (font (size 1.27 1.27) (thickness 0.15)) (justify left bottom) hide)
    )
    (property "Author" "Antmicro" (at 318.77 128.27 0)
      (effects (font (size 1.27 1.27) (thickness 0.15)) (justify left bottom) hide)
    )
    (property "License" "Apache-2.0" (at 318.77 130.81 0)
      (effects (font (size 1.27 1.27) (thickness 0.15)) (justify left bottom) hide)
    )
    (pin "1")
    (pin "2")
    (pin "3")
    (pin "4")
    (pin "5")
    (pin "6")
    (pin "8")
    (pin "9")
    (pin "10")
    (pin "11")
    (pin "12")
    (pin "13")
    (pin "14")
    (pin "15")
    (pin "7")
    (instances
      (project "kria-k26-devboard"
        (path ""
          (reference "U36") (unit 1)
        )
      )
    )
  )

  (symbol (lib_id "kria-k26-devboard:74LCX07_QFN") (at 293.37 91.44 0) (unit 2)
    (in_bom yes) (on_board yes) (dnp no) (fields_autoplaced)
    (property "Reference" "U36" (at 298.45 83.82 0)
      (effects (font (size 1.27 1.27)))
    )
    (property "Value" "74LCX07_QFN" (at 298.45 86.36 0)
      (effects (font (size 1.27 1.27) (thickness 0.15)) (justify left bottom))
    )
    (property "Footprint" "kria-k26-devboard-footprints:QFN-14-1EP_2.5x3mm_EP1.15x1.65mm_ONSemi_MLP14A" (at 295.91 100.33 0)
      (effects (font (size 1.27 1.27) (thickness 0.15)) (justify left bottom) hide)
    )
    (property "Datasheet" "https://www.mouser.com/datasheet/2/308/74LCX07_D-2309542.pdf" (at 293.37 91.44 0)
      (effects (font (size 1.27 1.27) (thickness 0.15)) (justify left bottom) hide)
    )
    (property "Manufacturer" "ON Semiconductor" (at 284.48 95.25 0)
      (effects (font (size 1.27 1.27) (thickness 0.15)) (justify left bottom) hide)
    )
    (property "MPN" "74LCX07BQX" (at 298.45 86.36 0)
      (effects (font (size 1.27 1.27) (thickness 0.15)) (justify left bottom) hide)
    )
    (property "Author" "Antmicro" (at 318.77 109.22 0)
      (effects (font (size 1.27 1.27) (thickness 0.15)) (justify left bottom) hide)
    )
    (property "License" "Apache-2.0" (at 318.77 111.76 0)
      (effects (font (size 1.27 1.27) (thickness 0.15)) (justify left bottom) hide)
    )
    (pin "3")
    (pin "4")
    (pin "1")
    (pin "2")
    (pin "5")
    (pin "6")
    (pin "8")
    (pin "9")
    (pin "10")
    (pin "11")
    (pin "12")
    (pin "13")
    (pin "14")
    (pin "15")
    (pin "7")
    (instances
      (project "kria-k26-devboard"
        (path ""
          (reference "U36") (unit 2)
        )
      )
    )
  )

  (symbol (lib_id "kria-k26-devboard:74LCX07_QFN") (at 293.37 78.74 0) (unit 3)
    (in_bom yes) (on_board yes) (dnp no) (fields_autoplaced)
    (property "Reference" "U36" (at 298.45 71.12 0)
      (effects (font (size 1.27 1.27)))
    )
    (property "Value" "74LCX07_QFN" (at 298.45 73.66 0)
      (effects (font (size 1.27 1.27) (thickness 0.15)) (justify left bottom))
    )
    (property "Footprint" "kria-k26-devboard-footprints:QFN-14-1EP_2.5x3mm_EP1.15x1.65mm_ONSemi_MLP14A" (at 295.91 87.63 0)
      (effects (font (size 1.27 1.27) (thickness 0.15)) (justify left bottom) hide)
    )
    (property "Datasheet" "https://www.mouser.com/datasheet/2/308/74LCX07_D-2309542.pdf" (at 293.37 78.74 0)
      (effects (font (size 1.27 1.27) (thickness 0.15)) (justify left bottom) hide)
    )
    (property "Manufacturer" "ON Semiconductor" (at 284.48 82.55 0)
      (effects (font (size 1.27 1.27) (thickness 0.15)) (justify left bottom) hide)
    )
    (property "MPN" "74LCX07BQX" (at 298.45 73.66 0)
      (effects (font (size 1.27 1.27) (thickness 0.15)) (justify left bottom) hide)
    )
    (property "Author" "Antmicro" (at 318.77 96.52 0)
      (effects (font (size 1.27 1.27) (thickness 0.15)) (justify left bottom) hide)
    )
    (property "License" "Apache-2.0" (at 318.77 99.06 0)
      (effects (font (size 1.27 1.27) (thickness 0.15)) (justify left bottom) hide)
    )
    (pin "5")
    (pin "6")
    (pin "1")
    (pin "2")
    (pin "3")
    (pin "4")
    (pin "8")
    (pin "9")
    (pin "10")
    (pin "11")
    (pin "12")
    (pin "13")
    (pin "14")
    (pin "15")
    (pin "7")
    (instances
      (project "kria-k26-devboard"
        (path ""
          (reference "U36") (unit 3)
        )
      )
    )
  )

  (symbol (lib_id "kria-k26-devboard:74LCX07_QFN") (at 293.37 66.04 0) (unit 4)
    (in_bom yes) (on_board yes) (dnp no) (fields_autoplaced)
    (property "Reference" "U36" (at 298.45 58.42 0)
      (effects (font (size 1.27 1.27)))
    )
    (property "Value" "74LCX07_QFN" (at 298.45 60.96 0)
      (effects (font (size 1.27 1.27) (thickness 0.15)) (justify left bottom))
    )
    (property "Footprint" "kria-k26-devboard-footprints:QFN-14-1EP_2.5x3mm_EP1.15x1.65mm_ONSemi_MLP14A" (at 295.91 74.93 0)
      (effects (font (size 1.27 1.27) (thickness 0.15)) (justify left bottom) hide)
    )
    (property "Datasheet" "https://www.mouser.com/datasheet/2/308/74LCX07_D-2309542.pdf" (at 293.37 66.04 0)
      (effects (font (size 1.27 1.27) (thickness 0.15)) (justify left bottom) hide)
    )
    (property "Manufacturer" "ON Semiconductor" (at 284.48 69.85 0)
      (effects (font (size 1.27 1.27) (thickness 0.15)) (justify left bottom) hide)
    )
    (property "MPN" "74LCX07BQX" (at 298.45 60.96 0)
      (effects (font (size 1.27 1.27) (thickness 0.15)) (justify left bottom) hide)
    )
    (property "Author" "Antmicro" (at 318.77 83.82 0)
      (effects (font (size 1.27 1.27) (thickness 0.15)) (justify left bottom) hide)
    )
    (property "License" "Apache-2.0" (at 318.77 86.36 0)
      (effects (font (size 1.27 1.27) (thickness 0.15)) (justify left bottom) hide)
    )
    (pin "8")
    (pin "9")
    (pin "3")
    (pin "2")
    (pin "1")
    (pin "4")
    (pin "5")
    (pin "6")
    (pin "10")
    (pin "11")
    (pin "12")
    (pin "13")
    (pin "14")
    (pin "15")
    (pin "7")
    (instances
      (project "kria-k26-devboard"
        (path ""
          (reference "U36") (unit 4)
        )
      )
    )
  )

  (symbol (lib_id "kria-k26-devboard:74LCX07_QFN") (at 293.37 53.34 0) (unit 5)
    (in_bom yes) (on_board yes) (dnp no) (fields_autoplaced)
    (property "Reference" "U36" (at 298.45 45.72 0)
      (effects (font (size 1.27 1.27)))
    )
    (property "Value" "74LCX07_QFN" (at 298.45 48.26 0)
      (effects (font (size 1.27 1.27) (thickness 0.15)) (justify left bottom))
    )
    (property "Footprint" "kria-k26-devboard-footprints:QFN-14-1EP_2.5x3mm_EP1.15x1.65mm_ONSemi_MLP14A" (at 295.91 62.23 0)
      (effects (font (size 1.27 1.27) (thickness 0.15)) (justify left bottom) hide)
    )
    (property "Datasheet" "https://www.mouser.com/datasheet/2/308/74LCX07_D-2309542.pdf" (at 293.37 53.34 0)
      (effects (font (size 1.27 1.27) (thickness 0.15)) (justify left bottom) hide)
    )
    (property "Manufacturer" "ON Semiconductor" (at 284.48 57.15 0)
      (effects (font (size 1.27 1.27) (thickness 0.15)) (justify left bottom) hide)
    )
    (property "MPN" "74LCX07BQX" (at 298.45 48.26 0)
      (effects (font (size 1.27 1.27) (thickness 0.15)) (justify left bottom) hide)
    )
    (property "Author" "Antmicro" (at 318.77 71.12 0)
      (effects (font (size 1.27 1.27) (thickness 0.15)) (justify left bottom) hide)
    )
    (property "License" "Apache-2.0" (at 318.77 73.66 0)
      (effects (font (size 1.27 1.27) (thickness 0.15)) (justify left bottom) hide)
    )
    (pin "10")
    (pin "11")
    (pin "1")
    (pin "2")
    (pin "3")
    (pin "4")
    (pin "5")
    (pin "6")
    (pin "8")
    (pin "9")
    (pin "12")
    (pin "13")
    (pin "14")
    (pin "15")
    (pin "7")
    (instances
      (project "kria-k26-devboard"
        (path ""
          (reference "U36") (unit 5)
        )
      )
    )
  )

  (symbol (lib_id "kria-k26-devboard:74LCX07_QFN") (at 306.07 137.16 0) (unit 7)
    (in_bom yes) (on_board yes) (dnp no) (fields_autoplaced)
    (property "Reference" "U36" (at 317.5 138.4299 0)
      (effects (font (size 1.27 1.27)) (justify left))
    )
    (property "Value" "74LCX07_QFN" (at 331.47 142.24 0)
      (effects (font (size 1.27 1.27) (thickness 0.15)) (justify left bottom))
    )
    (property "Footprint" "kria-k26-devboard-footprints:QFN-14-1EP_2.5x3mm_EP1.15x1.65mm_ONSemi_MLP14A" (at 331.47 144.78 0)
      (effects (font (size 1.27 1.27) (thickness 0.15)) (justify left bottom) hide)
    )
    (property "Datasheet" "https://www.mouser.com/datasheet/2/308/74LCX07_D-2309542.pdf" (at 331.47 147.32 0)
      (effects (font (size 1.27 1.27) (thickness 0.15)) (justify left bottom) hide)
    )
    (property "Manufacturer" "ON Semiconductor" (at 331.47 149.86 0)
      (effects (font (size 1.27 1.27) (thickness 0.15)) (justify left bottom) hide)
    )
    (property "MPN" "74LCX07BQX" (at 317.5 140.9699 0)
      (effects (font (size 1.27 1.27) (thickness 0.15)) (justify left bottom) hide)
    )
    (property "Author" "Antmicro" (at 331.47 154.94 0)
      (effects (font (size 1.27 1.27) (thickness 0.15)) (justify left bottom) hide)
    )
    (property "License" "Apache-2.0" (at 331.47 157.48 0)
      (effects (font (size 1.27 1.27) (thickness 0.15)) (justify left bottom) hide)
    )
    (pin "14")
    (pin "15")
    (pin "7")
    (pin "1")
    (pin "2")
    (pin "3")
    (pin "4")
    (pin "5")
    (pin "6")
    (pin "8")
    (pin "9")
    (pin "10")
    (pin "11")
    (pin "12")
    (pin "13")
    (instances
      (project "kria-k26-devboard"
        (path ""
          (reference "U36") (unit 7)
        )
      )
    )
  )

  (symbol (lib_id "kria-k26-devboard:GND") (at 111.76 157.48 0) (unit 1)
    (in_bom yes) (on_board yes) (dnp no) (fields_autoplaced)
    (property "Reference" "#PWR0300" (at 111.76 163.83 0)
      (effects (font (size 1.27 1.27)) hide)
    )
    (property "Value" "GND" (at 111.76 162.56 0)
      (effects (font (size 1.27 1.27)))
    )
    (property "Footprint" "" (at 120.65 165.1 0)
      (effects (font (size 1.27 1.27) (thickness 0.15)) (justify left bottom) hide)
    )
    (property "Datasheet" "" (at 120.65 170.18 0)
      (effects (font (size 1.27 1.27) (thickness 0.15)) (justify left bottom) hide)
    )
    (property "Author" "Antmicro" (at 120.65 165.1 0)
      (effects (font (size 1.27 1.27) (thickness 0.15)) (justify left bottom) hide)
    )
    (property "License" "Apache-2.0" (at 120.65 167.64 0)
      (effects (font (size 1.27 1.27) (thickness 0.15)) (justify left bottom) hide)
    )
    (pin "1")
    (instances
      (project "kria-k26-devboard"
        (path ""
          (reference "#PWR0300") (unit 1)
        )
      )
    )
  )

  (symbol (lib_id "kria-k26-devboard:R_10k_0402") (at 72.39 135.255 270) (unit 1)
    (in_bom yes) (on_board yes) (dnp no) (fields_autoplaced)
    (property "Reference" "R84" (at 69.85 136.525 90)
      (effects (font (size 1.524 1.524)) (justify right))
    )
    (property "Value" "R_10k_0402" (at 68.58 135.255 0)
      (effects (font (size 1.27 1.27) (thickness 0.15)) (justify left bottom) hide)
    )
    (property "Footprint" "kria-k26-devboard-footprints:R_0402_1005Metric" (at 77.47 140.335 0)
      (effects (font (size 1.27 1.27) (thickness 0.15)) (justify left bottom) hide)
    )
    (property "Datasheet" "https://www.bourns.com/docs/product-datasheets/cr.pdf" (at 72.39 135.255 0)
      (effects (font (size 1.27 1.27) (thickness 0.15)) (justify left bottom) hide)
    )
    (property "Manufacturer" "Bourns" (at 82.55 140.335 0)
      (effects (font (size 1.27 1.27) (thickness 0.15)) (justify left bottom) hide)
    )
    (property "MPN" "CR0402-FX-1002GLF" (at 80.01 140.335 0)
      (effects (font (size 1.27 1.27) (thickness 0.15)) (justify left bottom) hide)
    )
    (property "Val" "10k" (at 69.85 139.6999 90)
      (effects (font (size 1.27 1.27) (thickness 0.15)) (justify right))
    )
    (property "License" "Apache-2.0" (at 46.99 155.575 0)
      (effects (font (size 1.27 1.27) (thickness 0.15)) (justify left bottom) hide)
    )
    (property "Author" "Antmicro" (at 44.45 155.575 0)
      (effects (font (size 1.27 1.27) (thickness 0.15)) (justify left bottom) hide)
    )
    (property "Tolerance" "1%" (at 62.23 155.575 0)
      (effects (font (size 1.27 1.27)) (justify left bottom) hide)
    )
    (pin "1")
    (pin "2")
    (instances
      (project "kria-k26-devboard"
        (path ""
          (reference "R84") (unit 1)
        )
      )
    )
  )

  (symbol (lib_id "kria-k26-devboard:GND") (at 222.885 206.375 0) (unit 1)
    (in_bom yes) (on_board yes) (dnp no) (fields_autoplaced)
    (property "Reference" "#PWR0311" (at 222.885 212.725 0)
      (effects (font (size 1.27 1.27)) hide)
    )
    (property "Value" "GND" (at 222.885 210.82 0)
      (effects (font (size 1.27 1.27)))
    )
    (property "Footprint" "" (at 231.775 213.995 0)
      (effects (font (size 1.27 1.27) (thickness 0.15)) (justify left bottom) hide)
    )
    (property "Datasheet" "" (at 231.775 219.075 0)
      (effects (font (size 1.27 1.27) (thickness 0.15)) (justify left bottom) hide)
    )
    (property "Author" "Antmicro" (at 231.775 213.995 0)
      (effects (font (size 1.27 1.27) (thickness 0.15)) (justify left bottom) hide)
    )
    (property "License" "Apache-2.0" (at 231.775 216.535 0)
      (effects (font (size 1.27 1.27) (thickness 0.15)) (justify left bottom) hide)
    )
    (pin "1")
    (instances
      (project "kria-k26-devboard"
        (path ""
          (reference "#PWR0311") (unit 1)
        )
      )
    )
  )

  (symbol (lib_id "kria-k26-devboard:74AVC4T245_UQFN") (at 196.85 43.18 0) (mirror y) (unit 1)
    (in_bom yes) (on_board yes) (dnp no)
    (property "Reference" "U33" (at 187.325 33.655 0)
      (effects (font (size 1.27 1.27)))
    )
    (property "Value" "74AVC4T245_UQFN" (at 187.325 35.56 0)
      (effects (font (size 1.27 1.27) (thickness 0.15)) (justify left bottom))
    )
    (property "Footprint" "kria-k26-devboard-footprints:UQFN-16-1.8x2.6mm_P0.4mm_Texas_RSV0016A" (at 176.53 62.23 0)
      (effects (font (size 1.27 1.27) (thickness 0.15)) (justify left bottom) hide)
    )
    (property "Datasheet" "https://www.ti.com/lit/ds/symlink/sn74avc4t245.pdf" (at 198.12 49.53 0)
      (effects (font (size 1.27 1.27) (thickness 0.15)) (justify left bottom) hide)
    )
    (property "MPN" "74AVC4T245RSVRG4" (at 187.325 36.195 0)
      (effects (font (size 1.27 1.27) (thickness 0.15)) (justify left bottom) hide)
    )
    (property "Manufacturer" "Texas Instruments" (at 186.69 57.15 0)
      (effects (font (size 1.27 1.27) (thickness 0.15)) (justify left bottom) hide)
    )
    (property "Author" "Antmicro" (at 158.75 60.96 0)
      (effects (font (size 1.27 1.27) (thickness 0.15)) (justify left bottom) hide)
    )
    (property "License" "Apache-2.0" (at 158.75 63.5 0)
      (effects (font (size 1.27 1.27) (thickness 0.15)) (justify left bottom) hide)
    )
    (pin "1")
    (pin "10")
    (pin "11")
    (pin "12")
    (pin "13")
    (pin "14")
    (pin "15")
    (pin "16")
    (pin "2")
    (pin "3")
    (pin "4")
    (pin "5")
    (pin "6")
    (pin "7")
    (pin "8")
    (pin "9")
    (instances
      (project "kria-k26-devboard"
        (path ""
          (reference "U33") (unit 1)
        )
      )
    )
  )

  (symbol (lib_id "kria-k26-devboard:DTC014T_SOT-416") (at 64.77 151.13 0) (unit 1)
    (in_bom yes) (on_board yes) (dnp no) (fields_autoplaced)
    (property "Reference" "Q8" (at 74.93 149.8599 0)
      (effects (font (size 1.27 1.27)) (justify left))
    )
    (property "Value" "DTC014T_SOT-416" (at 74.93 152.3999 0)
      (effects (font (size 1.27 1.27) (thickness 0.15)) (justify left) hide)
    )
    (property "Footprint" "kria-k26-devboard-footprints:SOT-416" (at 69.85 158.75 0)
      (effects (font (size 1.27 1.27) (thickness 0.15)) (justify left bottom) hide)
    )
    (property "Datasheet" "https://www.rohm.com/datasheet?p=DTC014TEB&dist=Mouser&media=referral&source=mouser.com&campaign=Mouser" (at 64.77 151.13 0)
      (effects (font (size 1.27 1.27) (thickness 0.15)) (justify left bottom) hide)
    )
    (property "Manufacturer" "ROHM Semiconductor" (at 80.01 153.67 0)
      (effects (font (size 1.27 1.27) (thickness 0.15)) (justify left bottom) hide)
    )
    (property "MPN" "DTC014TEBTL" (at 74.93 152.3999 0)
      (effects (font (size 1.27 1.27) (thickness 0.15)) (justify left))
    )
    (property "Author" "Antmicro" (at 90.17 171.45 0)
      (effects (font (size 1.27 1.27) (thickness 0.15)) (justify left bottom) hide)
    )
    (property "License" "Apache-2.0" (at 90.17 173.99 0)
      (effects (font (size 1.27 1.27) (thickness 0.15)) (justify left bottom) hide)
    )
    (pin "1")
    (pin "2")
    (pin "3")
    (instances
      (project "kria-k26-devboard"
        (path ""
          (reference "Q8") (unit 1)
        )
      )
    )
  )

  (symbol (lib_id "kria-k26-devboard:DTC014T_SOT-416") (at 104.14 152.4 0) (unit 1)
    (in_bom yes) (on_board yes) (dnp no) (fields_autoplaced)
    (property "Reference" "Q9" (at 114.3 151.1299 0)
      (effects (font (size 1.27 1.27)) (justify left))
    )
    (property "Value" "DTC014T_SOT-416" (at 114.3 153.6699 0)
      (effects (font (size 1.27 1.27) (thickness 0.15)) (justify left) hide)
    )
    (property "Footprint" "kria-k26-devboard-footprints:SOT-416" (at 109.22 160.02 0)
      (effects (font (size 1.27 1.27) (thickness 0.15)) (justify left bottom) hide)
    )
    (property "Datasheet" "https://www.rohm.com/datasheet?p=DTC014TEB&dist=Mouser&media=referral&source=mouser.com&campaign=Mouser" (at 104.14 152.4 0)
      (effects (font (size 1.27 1.27) (thickness 0.15)) (justify left bottom) hide)
    )
    (property "Manufacturer" "ROHM Semiconductor" (at 119.38 154.94 0)
      (effects (font (size 1.27 1.27) (thickness 0.15)) (justify left bottom) hide)
    )
    (property "MPN" "DTC014TEBTL" (at 114.3 153.6699 0)
      (effects (font (size 1.27 1.27) (thickness 0.15)) (justify left))
    )
    (property "Author" "Antmicro" (at 129.54 172.72 0)
      (effects (font (size 1.27 1.27) (thickness 0.15)) (justify left bottom) hide)
    )
    (property "License" "Apache-2.0" (at 129.54 175.26 0)
      (effects (font (size 1.27 1.27) (thickness 0.15)) (justify left bottom) hide)
    )
    (pin "1")
    (pin "2")
    (pin "3")
    (instances
      (project "kria-k26-devboard"
        (path ""
          (reference "Q9") (unit 1)
        )
      )
    )
  )

  (symbol (lib_id "kria-k26-devboard:TP_0.75mm_SMD") (at 354.965 133.985 90) (unit 1)
    (in_bom yes) (on_board yes) (dnp no)
    (property "Reference" "TP17" (at 354.965 127 0)
      (effects (font (size 1.27 1.27)))
    )
    (property "Value" "TP_0.75mm_SMD" (at 357.505 133.985 0)
      (effects (font (size 1.27 1.27) (thickness 0.15)) (justify left bottom) hide)
    )
    (property "Footprint" "kria-k26-devboard-footprints:TP_SMD_0.75mm" (at 349.885 128.905 0)
      (effects (font (size 1.27 1.27) (thickness 0.15)) (justify left bottom) hide)
    )
    (property "Datasheet" "" (at 347.345 128.905 0)
      (effects (font (size 1.27 1.27) (thickness 0.15)) (justify left bottom) hide)
    )
    (property "MPN" "" (at 370.205 116.205 0)
      (effects (font (size 1.27 1.27) (thickness 0.15)) (justify left bottom) hide)
    )
    (property "Manufacturer" "" (at 372.745 116.205 0)
      (effects (font (size 1.27 1.27) (thickness 0.15)) (justify left bottom) hide)
    )
    (property "Author" "Antmicro" (at 375.285 116.205 0)
      (effects (font (size 1.27 1.27) (thickness 0.15)) (justify left bottom) hide)
    )
    (property "License" "Apache-2.0" (at 377.825 116.205 0)
      (effects (font (size 1.27 1.27) (thickness 0.15)) (justify left bottom) hide)
    )
    (pin "1")
    (instances
      (project "kria-k26-devboard"
        (path ""
          (reference "TP17") (unit 1)
        )
      )
    )
  )

  (symbol (lib_id "kria-k26-devboard:TP_0.75mm_SMD") (at 357.505 133.985 90) (unit 1)
    (in_bom yes) (on_board yes) (dnp no)
    (property "Reference" "TP18" (at 357.505 127 0)
      (effects (font (size 1.27 1.27)))
    )
    (property "Value" "TP_0.75mm_SMD" (at 360.045 133.985 0)
      (effects (font (size 1.27 1.27) (thickness 0.15)) (justify left bottom) hide)
    )
    (property "Footprint" "kria-k26-devboard-footprints:TP_SMD_0.75mm" (at 352.425 128.905 0)
      (effects (font (size 1.27 1.27) (thickness 0.15)) (justify left bottom) hide)
    )
    (property "Datasheet" "" (at 349.885 128.905 0)
      (effects (font (size 1.27 1.27) (thickness 0.15)) (justify left bottom) hide)
    )
    (property "MPN" "" (at 372.745 116.205 0)
      (effects (font (size 1.27 1.27) (thickness 0.15)) (justify left bottom) hide)
    )
    (property "Manufacturer" "" (at 375.285 116.205 0)
      (effects (font (size 1.27 1.27) (thickness 0.15)) (justify left bottom) hide)
    )
    (property "Author" "Antmicro" (at 377.825 116.205 0)
      (effects (font (size 1.27 1.27) (thickness 0.15)) (justify left bottom) hide)
    )
    (property "License" "Apache-2.0" (at 380.365 116.205 0)
      (effects (font (size 1.27 1.27) (thickness 0.15)) (justify left bottom) hide)
    )
    (pin "1")
    (instances
      (project "kria-k26-devboard"
        (path ""
          (reference "TP18") (unit 1)
        )
      )
    )
  )

  (symbol (lib_id "kria-k26-devboard:TP_0.75mm_SMD") (at 360.045 133.985 90) (unit 1)
    (in_bom yes) (on_board yes) (dnp no)
    (property "Reference" "TP19" (at 360.045 127 0)
      (effects (font (size 1.27 1.27)))
    )
    (property "Value" "TP_0.75mm_SMD" (at 362.585 133.985 0)
      (effects (font (size 1.27 1.27) (thickness 0.15)) (justify left bottom) hide)
    )
    (property "Footprint" "kria-k26-devboard-footprints:TP_SMD_0.75mm" (at 354.965 128.905 0)
      (effects (font (size 1.27 1.27) (thickness 0.15)) (justify left bottom) hide)
    )
    (property "Datasheet" "" (at 352.425 128.905 0)
      (effects (font (size 1.27 1.27) (thickness 0.15)) (justify left bottom) hide)
    )
    (property "MPN" "" (at 375.285 116.205 0)
      (effects (font (size 1.27 1.27) (thickness 0.15)) (justify left bottom) hide)
    )
    (property "Manufacturer" "" (at 377.825 116.205 0)
      (effects (font (size 1.27 1.27) (thickness 0.15)) (justify left bottom) hide)
    )
    (property "Author" "Antmicro" (at 380.365 116.205 0)
      (effects (font (size 1.27 1.27) (thickness 0.15)) (justify left bottom) hide)
    )
    (property "License" "Apache-2.0" (at 382.905 116.205 0)
      (effects (font (size 1.27 1.27) (thickness 0.15)) (justify left bottom) hide)
    )
    (pin "1")
    (instances
      (project "kria-k26-devboard"
        (path ""
          (reference "TP19") (unit 1)
        )
      )
    )
  )

  (symbol (lib_id "kria-k26-devboard:TP_0.75mm_SMD") (at 362.585 133.985 90) (unit 1)
    (in_bom yes) (on_board yes) (dnp no)
    (property "Reference" "TP20" (at 362.585 127 0)
      (effects (font (size 1.27 1.27)))
    )
    (property "Value" "TP_0.75mm_SMD" (at 365.125 133.985 0)
      (effects (font (size 1.27 1.27) (thickness 0.15)) (justify left bottom) hide)
    )
    (property "Footprint" "kria-k26-devboard-footprints:TP_SMD_0.75mm" (at 357.505 128.905 0)
      (effects (font (size 1.27 1.27) (thickness 0.15)) (justify left bottom) hide)
    )
    (property "Datasheet" "" (at 354.965 128.905 0)
      (effects (font (size 1.27 1.27) (thickness 0.15)) (justify left bottom) hide)
    )
    (property "MPN" "" (at 377.825 116.205 0)
      (effects (font (size 1.27 1.27) (thickness 0.15)) (justify left bottom) hide)
    )
    (property "Manufacturer" "" (at 380.365 116.205 0)
      (effects (font (size 1.27 1.27) (thickness 0.15)) (justify left bottom) hide)
    )
    (property "Author" "Antmicro" (at 382.905 116.205 0)
      (effects (font (size 1.27 1.27) (thickness 0.15)) (justify left bottom) hide)
    )
    (property "License" "Apache-2.0" (at 385.445 116.205 0)
      (effects (font (size 1.27 1.27) (thickness 0.15)) (justify left bottom) hide)
    )
    (pin "1")
    (instances
      (project "kria-k26-devboard"
        (path ""
          (reference "TP20") (unit 1)
        )
      )
    )
  )

  (symbol (lib_id "kria-k26-devboard:TP_0.75mm_SMD") (at 365.125 133.985 90) (unit 1)
    (in_bom yes) (on_board yes) (dnp no)
    (property "Reference" "TP22" (at 365.125 127 0)
      (effects (font (size 1.27 1.27)))
    )
    (property "Value" "TP_0.75mm_SMD" (at 367.665 133.985 0)
      (effects (font (size 1.27 1.27) (thickness 0.15)) (justify left bottom) hide)
    )
    (property "Footprint" "kria-k26-devboard-footprints:TP_SMD_0.75mm" (at 360.045 128.905 0)
      (effects (font (size 1.27 1.27) (thickness 0.15)) (justify left bottom) hide)
    )
    (property "Datasheet" "" (at 357.505 128.905 0)
      (effects (font (size 1.27 1.27) (thickness 0.15)) (justify left bottom) hide)
    )
    (property "MPN" "" (at 380.365 116.205 0)
      (effects (font (size 1.27 1.27) (thickness 0.15)) (justify left bottom) hide)
    )
    (property "Manufacturer" "" (at 382.905 116.205 0)
      (effects (font (size 1.27 1.27) (thickness 0.15)) (justify left bottom) hide)
    )
    (property "Author" "Antmicro" (at 385.445 116.205 0)
      (effects (font (size 1.27 1.27) (thickness 0.15)) (justify left bottom) hide)
    )
    (property "License" "Apache-2.0" (at 387.985 116.205 0)
      (effects (font (size 1.27 1.27) (thickness 0.15)) (justify left bottom) hide)
    )
    (pin "1")
    (instances
      (project "kria-k26-devboard"
        (path ""
          (reference "TP22") (unit 1)
        )
      )
    )
  )

  (symbol (lib_id "kria-k26-devboard:TP_0.75mm_SMD") (at 367.665 133.985 90) (unit 1)
    (in_bom yes) (on_board yes) (dnp no)
    (property "Reference" "TP23" (at 367.665 127 0)
      (effects (font (size 1.27 1.27)))
    )
    (property "Value" "TP_0.75mm_SMD" (at 370.205 133.985 0)
      (effects (font (size 1.27 1.27) (thickness 0.15)) (justify left bottom) hide)
    )
    (property "Footprint" "kria-k26-devboard-footprints:TP_SMD_0.75mm" (at 362.585 128.905 0)
      (effects (font (size 1.27 1.27) (thickness 0.15)) (justify left bottom) hide)
    )
    (property "Datasheet" "" (at 360.045 128.905 0)
      (effects (font (size 1.27 1.27) (thickness 0.15)) (justify left bottom) hide)
    )
    (property "MPN" "" (at 382.905 116.205 0)
      (effects (font (size 1.27 1.27) (thickness 0.15)) (justify left bottom) hide)
    )
    (property "Manufacturer" "" (at 385.445 116.205 0)
      (effects (font (size 1.27 1.27) (thickness 0.15)) (justify left bottom) hide)
    )
    (property "Author" "Antmicro" (at 387.985 116.205 0)
      (effects (font (size 1.27 1.27) (thickness 0.15)) (justify left bottom) hide)
    )
    (property "License" "Apache-2.0" (at 390.525 116.205 0)
      (effects (font (size 1.27 1.27) (thickness 0.15)) (justify left bottom) hide)
    )
    (pin "1")
    (instances
      (project "kria-k26-devboard"
        (path ""
          (reference "TP23") (unit 1)
        )
      )
    )
  )

  (symbol (lib_id "kria-k26-devboard:TP_0.75mm_SMD") (at 361.95 154.94 180) (unit 1)
    (in_bom yes) (on_board yes) (dnp no) (fields_autoplaced)
    (property "Reference" "TP21" (at 358.775 158.115 0)
      (effects (font (size 1.27 1.27)))
    )
    (property "Value" "TP_0.75mm_SMD" (at 361.95 152.4 0)
      (effects (font (size 1.27 1.27) (thickness 0.15)) (justify left bottom) hide)
    )
    (property "Footprint" "kria-k26-devboard-footprints:TP_SMD_0.75mm" (at 356.87 160.02 0)
      (effects (font (size 1.27 1.27) (thickness 0.15)) (justify left bottom) hide)
    )
    (property "Datasheet" "" (at 356.87 162.56 0)
      (effects (font (size 1.27 1.27) (thickness 0.15)) (justify left bottom) hide)
    )
    (property "MPN" "" (at 344.17 139.7 0)
      (effects (font (size 1.27 1.27) (thickness 0.15)) (justify left bottom) hide)
    )
    (property "Manufacturer" "" (at 344.17 137.16 0)
      (effects (font (size 1.27 1.27) (thickness 0.15)) (justify left bottom) hide)
    )
    (property "Author" "Antmicro" (at 344.17 134.62 0)
      (effects (font (size 1.27 1.27) (thickness 0.15)) (justify left bottom) hide)
    )
    (property "License" "Apache-2.0" (at 344.17 132.08 0)
      (effects (font (size 1.27 1.27) (thickness 0.15)) (justify left bottom) hide)
    )
    (pin "1")
    (instances
      (project "kria-k26-devboard"
        (path ""
          (reference "TP21") (unit 1)
        )
      )
    )
  )

  (symbol (lib_id "kria-k26-devboard:TP_0.75mm_SMD") (at 77.47 142.24 90) (unit 1)
    (in_bom yes) (on_board yes) (dnp no) (fields_autoplaced)
    (property "Reference" "TP13" (at 80.01 139.0649 90)
      (effects (font (size 1.27 1.27)) (justify right))
    )
    (property "Value" "TP_0.75mm_SMD" (at 80.01 142.24 0)
      (effects (font (size 1.27 1.27) (thickness 0.15)) (justify left bottom) hide)
    )
    (property "Footprint" "kria-k26-devboard-footprints:TP_SMD_0.75mm" (at 72.39 137.16 0)
      (effects (font (size 1.27 1.27) (thickness 0.15)) (justify left bottom) hide)
    )
    (property "Datasheet" "" (at 69.85 137.16 0)
      (effects (font (size 1.27 1.27) (thickness 0.15)) (justify left bottom) hide)
    )
    (property "MPN" "" (at 92.71 124.46 0)
      (effects (font (size 1.27 1.27) (thickness 0.15)) (justify left bottom) hide)
    )
    (property "Manufacturer" "" (at 95.25 124.46 0)
      (effects (font (size 1.27 1.27) (thickness 0.15)) (justify left bottom) hide)
    )
    (property "Author" "Antmicro" (at 97.79 124.46 0)
      (effects (font (size 1.27 1.27) (thickness 0.15)) (justify left bottom) hide)
    )
    (property "License" "Apache-2.0" (at 100.33 124.46 0)
      (effects (font (size 1.27 1.27) (thickness 0.15)) (justify left bottom) hide)
    )
    (pin "1")
    (instances
      (project "kria-k26-devboard"
        (path ""
          (reference "TP13") (unit 1)
        )
      )
    )
  )

  (symbol (lib_id "kria-k26-devboard:TP_0.75mm_SMD") (at 115.57 143.51 90) (unit 1)
    (in_bom yes) (on_board yes) (dnp no) (fields_autoplaced)
    (property "Reference" "TP16" (at 118.11 140.3349 90)
      (effects (font (size 1.27 1.27)) (justify right))
    )
    (property "Value" "TP_0.75mm_SMD" (at 118.11 143.51 0)
      (effects (font (size 1.27 1.27) (thickness 0.15)) (justify left bottom) hide)
    )
    (property "Footprint" "kria-k26-devboard-footprints:TP_SMD_0.75mm" (at 110.49 138.43 0)
      (effects (font (size 1.27 1.27) (thickness 0.15)) (justify left bottom) hide)
    )
    (property "Datasheet" "" (at 107.95 138.43 0)
      (effects (font (size 1.27 1.27) (thickness 0.15)) (justify left bottom) hide)
    )
    (property "MPN" "" (at 130.81 125.73 0)
      (effects (font (size 1.27 1.27) (thickness 0.15)) (justify left bottom) hide)
    )
    (property "Manufacturer" "" (at 133.35 125.73 0)
      (effects (font (size 1.27 1.27) (thickness 0.15)) (justify left bottom) hide)
    )
    (property "Author" "Antmicro" (at 135.89 125.73 0)
      (effects (font (size 1.27 1.27) (thickness 0.15)) (justify left bottom) hide)
    )
    (property "License" "Apache-2.0" (at 138.43 125.73 0)
      (effects (font (size 1.27 1.27) (thickness 0.15)) (justify left bottom) hide)
    )
    (pin "1")
    (instances
      (project "kria-k26-devboard"
        (path ""
          (reference "TP16") (unit 1)
        )
      )
    )
  )

  (symbol (lib_id "kria-k26-devboard:TP_0.75mm_SMD") (at 92.71 226.06 90) (unit 1)
    (in_bom yes) (on_board yes) (dnp no) (fields_autoplaced)
    (property "Reference" "TP15" (at 95.25 222.8849 90)
      (effects (font (size 1.27 1.27)) (justify right))
    )
    (property "Value" "TP_0.75mm_SMD" (at 95.25 226.06 0)
      (effects (font (size 1.27 1.27) (thickness 0.15)) (justify left bottom) hide)
    )
    (property "Footprint" "kria-k26-devboard-footprints:TP_SMD_0.75mm" (at 87.63 220.98 0)
      (effects (font (size 1.27 1.27) (thickness 0.15)) (justify left bottom) hide)
    )
    (property "Datasheet" "" (at 85.09 220.98 0)
      (effects (font (size 1.27 1.27) (thickness 0.15)) (justify left bottom) hide)
    )
    (property "MPN" "" (at 107.95 208.28 0)
      (effects (font (size 1.27 1.27) (thickness 0.15)) (justify left bottom) hide)
    )
    (property "Manufacturer" "" (at 110.49 208.28 0)
      (effects (font (size 1.27 1.27) (thickness 0.15)) (justify left bottom) hide)
    )
    (property "Author" "Antmicro" (at 113.03 208.28 0)
      (effects (font (size 1.27 1.27) (thickness 0.15)) (justify left bottom) hide)
    )
    (property "License" "Apache-2.0" (at 115.57 208.28 0)
      (effects (font (size 1.27 1.27) (thickness 0.15)) (justify left bottom) hide)
    )
    (pin "1")
    (instances
      (project "kria-k26-devboard"
        (path ""
          (reference "TP15") (unit 1)
        )
      )
    )
  )

  (symbol (lib_id "kria-k26-devboard:TP_0.75mm_SMD") (at 97.79 41.91 90) (unit 1)
    (in_bom yes) (on_board yes) (dnp no) (fields_autoplaced)
    (property "Reference" "TP14" (at 100.33 38.7349 90)
      (effects (font (size 1.27 1.27)) (justify right))
    )
    (property "Value" "TP_0.75mm_SMD" (at 100.33 41.91 0)
      (effects (font (size 1.27 1.27) (thickness 0.15)) (justify left bottom) hide)
    )
    (property "Footprint" "kria-k26-devboard-footprints:TP_SMD_0.75mm" (at 92.71 36.83 0)
      (effects (font (size 1.27 1.27) (thickness 0.15)) (justify left bottom) hide)
    )
    (property "Datasheet" "" (at 90.17 36.83 0)
      (effects (font (size 1.27 1.27) (thickness 0.15)) (justify left bottom) hide)
    )
    (property "MPN" "" (at 113.03 24.13 0)
      (effects (font (size 1.27 1.27) (thickness 0.15)) (justify left bottom) hide)
    )
    (property "Manufacturer" "" (at 115.57 24.13 0)
      (effects (font (size 1.27 1.27) (thickness 0.15)) (justify left bottom) hide)
    )
    (property "Author" "Antmicro" (at 118.11 24.13 0)
      (effects (font (size 1.27 1.27) (thickness 0.15)) (justify left bottom) hide)
    )
    (property "License" "Apache-2.0" (at 120.65 24.13 0)
      (effects (font (size 1.27 1.27) (thickness 0.15)) (justify left bottom) hide)
    )
    (pin "1")
    (instances
      (project "kria-k26-devboard"
        (path ""
          (reference "TP14") (unit 1)
        )
      )
    )
  )

  (symbol (lib_id "kria-k26-devboard:GND") (at 72.39 156.21 0) (unit 1)
    (in_bom yes) (on_board yes) (dnp no) (fields_autoplaced)
    (property "Reference" "#PWR0296" (at 72.39 162.56 0)
      (effects (font (size 1.27 1.27)) hide)
    )
    (property "Value" "GND" (at 72.39 161.29 0)
      (effects (font (size 1.27 1.27)))
    )
    (property "Footprint" "" (at 81.28 163.83 0)
      (effects (font (size 1.27 1.27) (thickness 0.15)) (justify left bottom) hide)
    )
    (property "Datasheet" "" (at 81.28 168.91 0)
      (effects (font (size 1.27 1.27) (thickness 0.15)) (justify left bottom) hide)
    )
    (property "Author" "Antmicro" (at 81.28 163.83 0)
      (effects (font (size 1.27 1.27) (thickness 0.15)) (justify left bottom) hide)
    )
    (property "License" "Apache-2.0" (at 81.28 166.37 0)
      (effects (font (size 1.27 1.27) (thickness 0.15)) (justify left bottom) hide)
    )
    (pin "1")
    (instances
      (project "kria-k26-devboard"
        (path ""
          (reference "#PWR0296") (unit 1)
        )
      )
    )
  )

  (symbol (lib_id "kria-k26-devboard:R_100k_0402") (at 236.855 67.945 90) (unit 1)
    (in_bom yes) (on_board yes) (dnp no)
    (property "Reference" "R91" (at 238.125 64.135 90)
      (effects (font (size 1.524 1.524)) (justify right))
    )
    (property "Value" "R_100k_0402" (at 240.665 67.945 0)
      (effects (font (size 1.27 1.27) (thickness 0.15)) (justify left bottom) hide)
    )
    (property "Footprint" "kria-k26-devboard-footprints:R_0402_1005Metric" (at 231.775 62.865 0)
      (effects (font (size 1.27 1.27) (thickness 0.15)) (justify left bottom) hide)
    )
    (property "Datasheet" "https://www.bourns.com/docs/product-datasheets/cr.pdf" (at 236.855 67.945 0)
      (effects (font (size 1.27 1.27) (thickness 0.15)) (justify left bottom) hide)
    )
    (property "Manufacturer" "Bourns" (at 226.695 62.865 0)
      (effects (font (size 1.27 1.27) (thickness 0.15)) (justify left bottom) hide)
    )
    (property "MPN" "CR0402-FX-1003GLF" (at 229.235 62.865 0)
      (effects (font (size 1.27 1.27) (thickness 0.15)) (justify left bottom) hide)
    )
    (property "Val" "100k" (at 238.125 66.04 90)
      (effects (font (size 1.27 1.27) (thickness 0.15)) (justify right))
    )
    (property "License" "Apache-2.0" (at 262.255 47.625 0)
      (effects (font (size 1.27 1.27) (thickness 0.15)) (justify left bottom) hide)
    )
    (property "Author" "Antmicro" (at 264.795 47.625 0)
      (effects (font (size 1.27 1.27) (thickness 0.15)) (justify left bottom) hide)
    )
    (property "Tolerance" "1%" (at 247.015 47.625 0)
      (effects (font (size 1.27 1.27)) (justify left bottom) hide)
    )
    (pin "1")
    (pin "2")
    (instances
      (project "kria-k26-devboard"
        (path ""
          (reference "R91") (unit 1)
        )
      )
    )
  )

  (symbol (lib_id "kria-k26-devboard:R_100k_0402") (at 229.235 67.945 90) (unit 1)
    (in_bom yes) (on_board yes) (dnp no)
    (property "Reference" "R90" (at 230.505 64.135 90)
      (effects (font (size 1.524 1.524)) (justify right))
    )
    (property "Value" "R_100k_0402" (at 233.045 67.945 0)
      (effects (font (size 1.27 1.27) (thickness 0.15)) (justify left bottom) hide)
    )
    (property "Footprint" "kria-k26-devboard-footprints:R_0402_1005Metric" (at 224.155 62.865 0)
      (effects (font (size 1.27 1.27) (thickness 0.15)) (justify left bottom) hide)
    )
    (property "Datasheet" "https://www.bourns.com/docs/product-datasheets/cr.pdf" (at 229.235 67.945 0)
      (effects (font (size 1.27 1.27) (thickness 0.15)) (justify left bottom) hide)
    )
    (property "Manufacturer" "Bourns" (at 219.075 62.865 0)
      (effects (font (size 1.27 1.27) (thickness 0.15)) (justify left bottom) hide)
    )
    (property "MPN" "CR0402-FX-1003GLF" (at 221.615 62.865 0)
      (effects (font (size 1.27 1.27) (thickness 0.15)) (justify left bottom) hide)
    )
    (property "Val" "100k" (at 230.505 66.04 90)
      (effects (font (size 1.27 1.27) (thickness 0.15)) (justify right))
    )
    (property "License" "Apache-2.0" (at 254.635 47.625 0)
      (effects (font (size 1.27 1.27) (thickness 0.15)) (justify left bottom) hide)
    )
    (property "Author" "Antmicro" (at 257.175 47.625 0)
      (effects (font (size 1.27 1.27) (thickness 0.15)) (justify left bottom) hide)
    )
    (property "Tolerance" "1%" (at 239.395 47.625 0)
      (effects (font (size 1.27 1.27)) (justify left bottom) hide)
    )
    (pin "1")
    (pin "2")
    (instances
      (project "kria-k26-devboard"
        (path ""
          (reference "R90") (unit 1)
        )
      )
    )
  )

  (symbol (lib_id "kria-k26-devboard:R_100k_0402") (at 221.615 67.945 90) (unit 1)
    (in_bom yes) (on_board yes) (dnp no)
    (property "Reference" "R89" (at 222.885 64.135 90)
      (effects (font (size 1.524 1.524)) (justify right))
    )
    (property "Value" "R_100k_0402" (at 225.425 67.945 0)
      (effects (font (size 1.27 1.27) (thickness 0.15)) (justify left bottom) hide)
    )
    (property "Footprint" "kria-k26-devboard-footprints:R_0402_1005Metric" (at 216.535 62.865 0)
      (effects (font (size 1.27 1.27) (thickness 0.15)) (justify left bottom) hide)
    )
    (property "Datasheet" "https://www.bourns.com/docs/product-datasheets/cr.pdf" (at 221.615 67.945 0)
      (effects (font (size 1.27 1.27) (thickness 0.15)) (justify left bottom) hide)
    )
    (property "Manufacturer" "Bourns" (at 211.455 62.865 0)
      (effects (font (size 1.27 1.27) (thickness 0.15)) (justify left bottom) hide)
    )
    (property "MPN" "CR0402-FX-1003GLF" (at 213.995 62.865 0)
      (effects (font (size 1.27 1.27) (thickness 0.15)) (justify left bottom) hide)
    )
    (property "Val" "100k" (at 222.885 66.04 90)
      (effects (font (size 1.27 1.27) (thickness 0.15)) (justify right))
    )
    (property "License" "Apache-2.0" (at 247.015 47.625 0)
      (effects (font (size 1.27 1.27) (thickness 0.15)) (justify left bottom) hide)
    )
    (property "Author" "Antmicro" (at 249.555 47.625 0)
      (effects (font (size 1.27 1.27) (thickness 0.15)) (justify left bottom) hide)
    )
    (property "Tolerance" "1%" (at 231.775 47.625 0)
      (effects (font (size 1.27 1.27)) (justify left bottom) hide)
    )
    (pin "1")
    (pin "2")
    (instances
      (project "kria-k26-devboard"
        (path ""
          (reference "R89") (unit 1)
        )
      )
    )
  )

  (symbol (lib_id "kria-k26-devboard:R_100k_0402") (at 213.995 67.945 90) (unit 1)
    (in_bom yes) (on_board yes) (dnp no)
    (property "Reference" "R87" (at 215.265 64.135 90)
      (effects (font (size 1.524 1.524)) (justify right))
    )
    (property "Value" "R_100k_0402" (at 217.805 67.945 0)
      (effects (font (size 1.27 1.27) (thickness 0.15)) (justify left bottom) hide)
    )
    (property "Footprint" "kria-k26-devboard-footprints:R_0402_1005Metric" (at 208.915 62.865 0)
      (effects (font (size 1.27 1.27) (thickness 0.15)) (justify left bottom) hide)
    )
    (property "Datasheet" "https://www.bourns.com/docs/product-datasheets/cr.pdf" (at 213.995 67.945 0)
      (effects (font (size 1.27 1.27) (thickness 0.15)) (justify left bottom) hide)
    )
    (property "Manufacturer" "Bourns" (at 203.835 62.865 0)
      (effects (font (size 1.27 1.27) (thickness 0.15)) (justify left bottom) hide)
    )
    (property "MPN" "CR0402-FX-1003GLF" (at 206.375 62.865 0)
      (effects (font (size 1.27 1.27) (thickness 0.15)) (justify left bottom) hide)
    )
    (property "Val" "100k" (at 215.265 66.04 90)
      (effects (font (size 1.27 1.27) (thickness 0.15)) (justify right))
    )
    (property "License" "Apache-2.0" (at 239.395 47.625 0)
      (effects (font (size 1.27 1.27) (thickness 0.15)) (justify left bottom) hide)
    )
    (property "Author" "Antmicro" (at 241.935 47.625 0)
      (effects (font (size 1.27 1.27) (thickness 0.15)) (justify left bottom) hide)
    )
    (property "Tolerance" "1%" (at 224.155 47.625 0)
      (effects (font (size 1.27 1.27)) (justify left bottom) hide)
    )
    (pin "1")
    (pin "2")
    (instances
      (project "kria-k26-devboard"
        (path ""
          (reference "R87") (unit 1)
        )
      )
    )
  )

  (symbol (lib_id "kria-k26-devboard:SN74AVC2T245_UQFN") (at 196.215 106.68 0) (mirror y) (unit 1)
    (in_bom yes) (on_board yes) (dnp no)
    (property "Reference" "U34" (at 187.96 99.06 0)
      (effects (font (size 1.27 1.27)))
    )
    (property "Value" "SN74AVC2T245_UQFN" (at 187.96 101.6 0)
      (effects (font (size 1.27 1.27) (thickness 0.15)) (justify left bottom) hide)
    )
    (property "Footprint" "kria-k26-devboard-footprints:UQFN-10_1.4x1.8x0.5mm_P0.4mm" (at 196.215 106.68 0)
      (effects (font (size 1.27 1.27) (thickness 0.15)) (justify left bottom) hide)
    )
    (property "Datasheet" "https://www.ti.com/lit/ds/symlink/sn74avc2t245.pdf?ts=1678888074783&ref_url=https%253A%252F%252Fwww.google.com%252F" (at 196.215 106.68 0)
      (effects (font (size 1.27 1.27) (thickness 0.15)) (justify left bottom) hide)
    )
    (property "Manufacturer" "Texas Instruments" (at 196.215 106.68 0)
      (effects (font (size 1.27 1.27) (thickness 0.15)) (justify left bottom) hide)
    )
    (property "MPN" "SN74AVC2T245RSWR" (at 197.485 102.87 0)
      (effects (font (size 1.27 1.27) (thickness 0.15)) (justify left bottom))
    )
    (property "Author" "Antmicro" (at 150.495 124.46 0)
      (effects (font (size 1.27 1.27) (thickness 0.15)) (justify left bottom) hide)
    )
    (property "License" "Apache-2.0" (at 150.495 127 0)
      (effects (font (size 1.27 1.27) (thickness 0.15)) (justify left bottom) hide)
    )
    (pin "1")
    (pin "10")
    (pin "2")
    (pin "3")
    (pin "4")
    (pin "5")
    (pin "6")
    (pin "7")
    (pin "8")
    (pin "9")
    (instances
      (project "kria-k26-devboard"
        (path ""
          (reference "U34") (unit 1)
        )
      )
    )
  )

  (symbol (lib_id "kria-k26-devboard:C_100n_0402") (at 160.655 114.935 270) (unit 1)
    (in_bom yes) (on_board yes) (dnp no) (fields_autoplaced)
    (property "Reference" "C137" (at 163.83 116.2113 90)
      (effects (font (size 1.524 1.524)) (justify left))
    )
    (property "Value" "C_100n_0402" (at 156.845 114.935 0)
      (effects (font (size 1.27 1.27) (thickness 0.15)) (justify left bottom) hide)
    )
    (property "Footprint" "kria-k26-devboard-footprints:C_0402_1005Metric" (at 165.735 120.015 0)
      (effects (font (size 1.27 1.27) (thickness 0.15)) (justify left bottom) hide)
    )
    (property "Datasheet" "https://search.murata.co.jp/Ceramy/image/img/A01X/G101/ENG/GRM155R61H104KE14-01.pdf" (at 160.655 114.935 0)
      (effects (font (size 1.27 1.27) (thickness 0.15)) (justify left bottom) hide)
    )
    (property "Manufacturer" "Murata" (at 170.815 120.015 0)
      (effects (font (size 1.27 1.27) (thickness 0.15)) (justify left bottom) hide)
    )
    (property "MPN" "GRM155R61H104KE14D" (at 168.275 120.015 0)
      (effects (font (size 1.27 1.27) (thickness 0.15)) (justify left bottom) hide)
    )
    (property "Val" "100n" (at 163.83 119.3862 90)
      (effects (font (size 1.27 1.27) (thickness 0.15)) (justify left))
    )
    (property "License" "Apache-2.0" (at 137.795 135.255 0)
      (effects (font (size 1.27 1.27) (thickness 0.15)) (justify left bottom) hide)
    )
    (property "Author" "Antmicro" (at 135.255 135.255 0)
      (effects (font (size 1.27 1.27) (thickness 0.15)) (justify left bottom) hide)
    )
    (property "Voltage" "50V" (at 132.715 135.255 0)
      (effects (font (size 1.27 1.27)) (justify left bottom) hide)
    )
    (property "Dielectric" "X5R" (at 130.175 135.255 0)
      (effects (font (size 1.27 1.27)) (justify left bottom) hide)
    )
    (pin "1")
    (pin "2")
    (instances
      (project "kria-k26-devboard"
        (path ""
          (reference "C137") (unit 1)
        )
      )
    )
  )

  (symbol (lib_id "kria-k26-devboard:GND") (at 160.655 120.015 0) (unit 1)
    (in_bom yes) (on_board yes) (dnp no) (fields_autoplaced)
    (property "Reference" "#PWR0307" (at 160.655 126.365 0)
      (effects (font (size 1.27 1.27)) hide)
    )
    (property "Value" "GND" (at 160.655 125.603 0)
      (effects (font (size 1.27 1.27)))
    )
    (property "Footprint" "" (at 169.545 127.635 0)
      (effects (font (size 1.27 1.27) (thickness 0.15)) (justify left bottom) hide)
    )
    (property "Datasheet" "" (at 169.545 132.715 0)
      (effects (font (size 1.27 1.27) (thickness 0.15)) (justify left bottom) hide)
    )
    (property "Author" "Antmicro" (at 169.545 127.635 0)
      (effects (font (size 1.27 1.27) (thickness 0.15)) (justify left bottom) hide)
    )
    (property "License" "Apache-2.0" (at 169.545 130.175 0)
      (effects (font (size 1.27 1.27) (thickness 0.15)) (justify left bottom) hide)
    )
    (pin "1")
    (instances
      (project "kria-k26-devboard"
        (path ""
          (reference "#PWR0307") (unit 1)
        )
      )
    )
  )

  (symbol (lib_id "kria-k26-devboard:C_100n_0402") (at 160.655 130.175 270) (unit 1)
    (in_bom yes) (on_board yes) (dnp no) (fields_autoplaced)
    (property "Reference" "C138" (at 163.83 131.4513 90)
      (effects (font (size 1.524 1.524)) (justify left))
    )
    (property "Value" "C_100n_0402" (at 156.845 130.175 0)
      (effects (font (size 1.27 1.27) (thickness 0.15)) (justify left bottom) hide)
    )
    (property "Footprint" "kria-k26-devboard-footprints:C_0402_1005Metric" (at 165.735 135.255 0)
      (effects (font (size 1.27 1.27) (thickness 0.15)) (justify left bottom) hide)
    )
    (property "Datasheet" "https://search.murata.co.jp/Ceramy/image/img/A01X/G101/ENG/GRM155R61H104KE14-01.pdf" (at 160.655 130.175 0)
      (effects (font (size 1.27 1.27) (thickness 0.15)) (justify left bottom) hide)
    )
    (property "Manufacturer" "Murata" (at 170.815 135.255 0)
      (effects (font (size 1.27 1.27) (thickness 0.15)) (justify left bottom) hide)
    )
    (property "MPN" "GRM155R61H104KE14D" (at 168.275 135.255 0)
      (effects (font (size 1.27 1.27) (thickness 0.15)) (justify left bottom) hide)
    )
    (property "Val" "100n" (at 163.83 134.6262 90)
      (effects (font (size 1.27 1.27) (thickness 0.15)) (justify left))
    )
    (property "License" "Apache-2.0" (at 137.795 150.495 0)
      (effects (font (size 1.27 1.27) (thickness 0.15)) (justify left bottom) hide)
    )
    (property "Author" "Antmicro" (at 135.255 150.495 0)
      (effects (font (size 1.27 1.27) (thickness 0.15)) (justify left bottom) hide)
    )
    (property "Voltage" "50V" (at 132.715 150.495 0)
      (effects (font (size 1.27 1.27)) (justify left bottom) hide)
    )
    (property "Dielectric" "X5R" (at 130.175 150.495 0)
      (effects (font (size 1.27 1.27)) (justify left bottom) hide)
    )
    (pin "1")
    (pin "2")
    (instances
      (project "kria-k26-devboard"
        (path ""
          (reference "C138") (unit 1)
        )
      )
    )
  )

  (symbol (lib_id "kria-k26-devboard:GND") (at 160.655 135.255 0) (unit 1)
    (in_bom yes) (on_board yes) (dnp no) (fields_autoplaced)
    (property "Reference" "#PWR0310" (at 160.655 141.605 0)
      (effects (font (size 1.27 1.27)) hide)
    )
    (property "Value" "GND" (at 160.655 140.843 0)
      (effects (font (size 1.27 1.27)))
    )
    (property "Footprint" "" (at 169.545 142.875 0)
      (effects (font (size 1.27 1.27) (thickness 0.15)) (justify left bottom) hide)
    )
    (property "Datasheet" "" (at 169.545 147.955 0)
      (effects (font (size 1.27 1.27) (thickness 0.15)) (justify left bottom) hide)
    )
    (property "Author" "Antmicro" (at 169.545 142.875 0)
      (effects (font (size 1.27 1.27) (thickness 0.15)) (justify left bottom) hide)
    )
    (property "License" "Apache-2.0" (at 169.545 145.415 0)
      (effects (font (size 1.27 1.27) (thickness 0.15)) (justify left bottom) hide)
    )
    (pin "1")
    (instances
      (project "kria-k26-devboard"
        (path ""
          (reference "#PWR0310") (unit 1)
        )
      )
    )
  )

  (symbol (lib_id "kria-k26-devboard:R_100k_0402") (at 226.06 120.65 90) (unit 1)
    (in_bom yes) (on_board yes) (dnp no) (fields_autoplaced)
    (property "Reference" "R88" (at 223.52 116.84 90)
      (effects (font (size 1.524 1.524)) (justify left))
    )
    (property "Value" "R_100k_0402" (at 229.87 120.65 0)
      (effects (font (size 1.27 1.27) (thickness 0.15)) (justify left bottom) hide)
    )
    (property "Footprint" "kria-k26-devboard-footprints:R_0402_1005Metric" (at 220.98 115.57 0)
      (effects (font (size 1.27 1.27) (thickness 0.15)) (justify left bottom) hide)
    )
    (property "Datasheet" "https://www.bourns.com/docs/product-datasheets/cr.pdf" (at 226.06 120.65 0)
      (effects (font (size 1.27 1.27) (thickness 0.15)) (justify left bottom) hide)
    )
    (property "Manufacturer" "Bourns" (at 215.9 115.57 0)
      (effects (font (size 1.27 1.27) (thickness 0.15)) (justify left bottom) hide)
    )
    (property "MPN" "CR0402-FX-1003GLF" (at 218.44 115.57 0)
      (effects (font (size 1.27 1.27) (thickness 0.15)) (justify left bottom) hide)
    )
    (property "Val" "100k" (at 223.52 120.0149 90)
      (effects (font (size 1.27 1.27) (thickness 0.15)) (justify left))
    )
    (property "License" "Apache-2.0" (at 251.46 100.33 0)
      (effects (font (size 1.27 1.27) (thickness 0.15)) (justify left bottom) hide)
    )
    (property "Author" "Antmicro" (at 254 100.33 0)
      (effects (font (size 1.27 1.27) (thickness 0.15)) (justify left bottom) hide)
    )
    (property "Tolerance" "1%" (at 236.22 100.33 0)
      (effects (font (size 1.27 1.27)) (justify left bottom) hide)
    )
    (pin "1")
    (pin "2")
    (instances
      (project "kria-k26-devboard"
        (path ""
          (reference "R88") (unit 1)
        )
      )
    )
  )

  (symbol (lib_id "kria-k26-devboard:GND") (at 197.485 122.555 0) (unit 1)
    (in_bom yes) (on_board yes) (dnp no) (fields_autoplaced)
    (property "Reference" "#PWR0309" (at 197.485 128.905 0)
      (effects (font (size 1.27 1.27)) hide)
    )
    (property "Value" "GND" (at 197.485 127.635 0)
      (effects (font (size 1.27 1.27)))
    )
    (property "Footprint" "" (at 206.375 130.175 0)
      (effects (font (size 1.27 1.27) (thickness 0.15)) (justify left bottom) hide)
    )
    (property "Datasheet" "" (at 206.375 135.255 0)
      (effects (font (size 1.27 1.27) (thickness 0.15)) (justify left bottom) hide)
    )
    (property "Author" "Antmicro" (at 206.375 130.175 0)
      (effects (font (size 1.27 1.27) (thickness 0.15)) (justify left bottom) hide)
    )
    (property "License" "Apache-2.0" (at 206.375 132.715 0)
      (effects (font (size 1.27 1.27) (thickness 0.15)) (justify left bottom) hide)
    )
    (pin "1")
    (instances
      (project "kria-k26-devboard"
        (path ""
          (reference "#PWR0309") (unit 1)
        )
      )
    )
  )

  (symbol (lib_id "kria-k26-devboard:GND") (at 175.895 123.19 0) (unit 1)
    (in_bom yes) (on_board yes) (dnp no) (fields_autoplaced)
    (property "Reference" "#PWR0303" (at 175.895 129.54 0)
      (effects (font (size 1.27 1.27)) hide)
    )
    (property "Value" "GND" (at 175.895 128.27 0)
      (effects (font (size 1.27 1.27)))
    )
    (property "Footprint" "" (at 184.785 130.81 0)
      (effects (font (size 1.27 1.27) (thickness 0.15)) (justify left bottom) hide)
    )
    (property "Datasheet" "" (at 184.785 135.89 0)
      (effects (font (size 1.27 1.27) (thickness 0.15)) (justify left bottom) hide)
    )
    (property "Author" "Antmicro" (at 184.785 130.81 0)
      (effects (font (size 1.27 1.27) (thickness 0.15)) (justify left bottom) hide)
    )
    (property "License" "Apache-2.0" (at 184.785 133.35 0)
      (effects (font (size 1.27 1.27) (thickness 0.15)) (justify left bottom) hide)
    )
    (pin "1")
    (instances
      (project "kria-k26-devboard"
        (path ""
          (reference "#PWR0303") (unit 1)
        )
      )
    )
  )

  (symbol (lib_id "kria-k26-devboard:R_10k_0402") (at 311.15 101.6 270) (unit 1)
    (in_bom yes) (on_board yes) (dnp no) (fields_autoplaced)
    (property "Reference" "R93" (at 313.69 102.87 90)
      (effects (font (size 1.524 1.524)) (justify left))
    )
    (property "Value" "R_10k_0402" (at 307.34 101.6 0)
      (effects (font (size 1.27 1.27) (thickness 0.15)) (justify left bottom) hide)
    )
    (property "Footprint" "kria-k26-devboard-footprints:R_0402_1005Metric" (at 316.23 106.68 0)
      (effects (font (size 1.27 1.27) (thickness 0.15)) (justify left bottom) hide)
    )
    (property "Datasheet" "https://www.bourns.com/docs/product-datasheets/cr.pdf" (at 311.15 101.6 0)
      (effects (font (size 1.27 1.27) (thickness 0.15)) (justify left bottom) hide)
    )
    (property "Manufacturer" "Bourns" (at 321.31 106.68 0)
      (effects (font (size 1.27 1.27) (thickness 0.15)) (justify left bottom) hide)
    )
    (property "MPN" "CR0402-FX-1002GLF" (at 318.77 106.68 0)
      (effects (font (size 1.27 1.27) (thickness 0.15)) (justify left bottom) hide)
    )
    (property "Val" "10k" (at 313.69 106.0449 90)
      (effects (font (size 1.27 1.27) (thickness 0.15)) (justify left))
    )
    (property "License" "Apache-2.0" (at 285.75 121.92 0)
      (effects (font (size 1.27 1.27) (thickness 0.15)) (justify left bottom) hide)
    )
    (property "Author" "Antmicro" (at 283.21 121.92 0)
      (effects (font (size 1.27 1.27) (thickness 0.15)) (justify left bottom) hide)
    )
    (property "Tolerance" "1%" (at 300.99 121.92 0)
      (effects (font (size 1.27 1.27)) (justify left bottom) hide)
    )
    (pin "1")
    (pin "2")
    (instances
      (project "kria-k26-devboard"
        (path ""
          (reference "R93") (unit 1)
        )
      )
    )
  )

  (symbol (lib_id "kria-k26-devboard:JST_SH_1x8_BM08B-SRSS-TB-LF-SN") (at 373.38 154.94 0) (mirror x) (unit 1)
    (in_bom yes) (on_board yes) (dnp no) (fields_autoplaced)
    (property "Reference" "J7" (at 379.73 143.51 0)
      (effects (font (size 1.27 1.27)) (justify left))
    )
    (property "Value" "JST_SH_1x8_BM08B-SRSS-TB-LF-SN" (at 379.73 146.0499 0)
      (effects (font (size 1.27 1.27) (thickness 0.15)) (justify left bottom) hide)
    )
    (property "Footprint" "kria-k26-devboard-footprints:Conn_JST_SH_1x8_BM08B-SRSS-TB-LF-SN" (at 373.38 158.75 0)
      (effects (font (size 1.27 1.27) (thickness 0.15)) (justify left bottom) hide)
    )
    (property "Datasheet" "https://www.jst-mfg.com/product/pdf/eng/eSH.pdf?651faad4db779" (at 373.38 158.75 0)
      (effects (font (size 1.27 1.27) (thickness 0.15)) (justify left bottom) hide)
    )
    (property "MPN" "BM08B-SRSS-TB(LF)(SN)" (at 379.73 146.05 0)
      (effects (font (size 1.27 1.27) (thickness 0.15)) (justify left bottom))
    )
    (property "Manufacturer" "JST Automotive Connectors" (at 373.38 154.94 0)
      (effects (font (size 1.27 1.27) (thickness 0.15)) (justify left bottom) hide)
    )
    (property "Author" "Antmicro" (at 387.35 139.7 0)
      (effects (font (size 1.27 1.27) (thickness 0.15)) (justify left bottom) hide)
    )
    (property "License" "Apache-2.0" (at 387.35 137.16 0)
      (effects (font (size 1.27 1.27) (thickness 0.15)) (justify left bottom) hide)
    )
    (pin "1")
    (pin "2")
    (pin "3")
    (pin "4")
    (pin "5")
    (pin "6")
    (pin "7")
    (pin "8")
    (pin "MP")
    (instances
      (project "kria-k26-devboard"
        (path ""
          (reference "J7") (unit 1)
        )
      )
    )
  )

  (symbol (lib_id "kria-k26-devboard:SW_KMR211NGLFS_SMD") (at 34.29 45.72 0) (unit 1)
    (in_bom yes) (on_board yes) (dnp no) (fields_autoplaced)
    (property "Reference" "S1" (at 39.37 38.1 0)
      (effects (font (size 1.27 1.27)))
    )
    (property "Value" "SW_KMR211NGLFS_SMD" (at 39.37 40.64 0)
      (effects (font (size 1.27 1.27) (thickness 0.15)) (justify left bottom) hide)
    )
    (property "Footprint" "kria-k26-devboard-footprints:SW_KMR211NGLFS_SMD" (at 39.37 40.64 0)
      (effects (font (size 1.27 1.27) (thickness 0.15)) (justify left bottom) hide)
    )
    (property "Datasheet" "http://www.farnell.com/datasheets/2631211.pdf" (at 39.37 38.1 0)
      (effects (font (size 1.27 1.27) (thickness 0.15)) (justify left bottom) hide)
    )
    (property "MPN" "KMR211NGLFS" (at 39.37 40.64 0)
      (effects (font (size 1.27 1.27) (thickness 0.15)) (justify left bottom))
    )
    (property "Manufacturer" "C&K" (at 39.37 33.7312 0)
      (effects (font (size 1.27 1.27) (thickness 0.15)) (justify left bottom) hide)
    )
    (property "Author" "Antmicro" (at 59.69 63.5 0)
      (effects (font (size 1.27 1.27) (thickness 0.15)) (justify left bottom) hide)
    )
    (property "License" "Apache-2.0" (at 59.69 66.04 0)
      (effects (font (size 1.27 1.27) (thickness 0.15)) (justify left bottom) hide)
    )
    (pin "1")
    (pin "2")
    (pin "3")
    (pin "4")
    (instances
      (project "kria-k26-devboard"
        (path ""
          (reference "S1") (unit 1)
        )
      )
    )
  )

  (symbol (lib_id "kria-k26-devboard:GND") (at 31.75 49.53 0) (unit 1)
    (in_bom yes) (on_board yes) (dnp no) (fields_autoplaced)
    (property "Reference" "#PWR0293" (at 31.75 55.88 0)
      (effects (font (size 1.27 1.27)) hide)
    )
    (property "Value" "GND" (at 31.75 54.61 0)
      (effects (font (size 1.27 1.27)))
    )
    (property "Footprint" "" (at 40.64 57.15 0)
      (effects (font (size 1.27 1.27) (thickness 0.15)) (justify left bottom) hide)
    )
    (property "Datasheet" "" (at 40.64 62.23 0)
      (effects (font (size 1.27 1.27) (thickness 0.15)) (justify left bottom) hide)
    )
    (property "Author" "Antmicro" (at 40.64 57.15 0)
      (effects (font (size 1.27 1.27) (thickness 0.15)) (justify left bottom) hide)
    )
    (property "License" "Apache-2.0" (at 40.64 59.69 0)
      (effects (font (size 1.27 1.27) (thickness 0.15)) (justify left bottom) hide)
    )
    (pin "1")
    (instances
      (project "kria-k26-devboard"
        (path ""
          (reference "#PWR0293") (unit 1)
        )
      )
    )
  )

  (symbol (lib_id "kria-k26-devboard:TPS3840PH30DBVR") (at 70.485 44.45 0) (unit 1)
    (in_bom yes) (on_board yes) (dnp no) (fields_autoplaced)
    (property "Reference" "U31" (at 80.01 35.56 0)
      (effects (font (size 1.524 1.524)))
    )
    (property "Value" "TPS3840PH30DBVR" (at 80.01 39.37 0)
      (effects (font (size 1.27 1.27) (thickness 0.15)) (justify left bottom))
    )
    (property "Footprint" "kria-k26-devboard-footprints:SOT-23-5" (at 61.595 57.15 0)
      (effects (font (size 1.27 1.27) (thickness 0.15)) (justify left bottom) hide)
    )
    (property "Datasheet" "https://www.ti.com/lit/ds/symlink/tps3840.pdf?HQS=dis-mous-null-mousermode-dsf-pf-null-wwe&DCM=yes&ref_url=https%3A%2F%2Fwww.mouser.com%2F&distId=26" (at 70.485 44.45 0)
      (effects (font (size 1.27 1.27) (thickness 0.15)) (justify left bottom) hide)
    )
    (property "Manufacturer" "Texas Instruments" (at 67.945 52.07 0)
      (effects (font (size 1.27 1.27) (thickness 0.15)) (justify left bottom) hide)
    )
    (property "MPN" "TPS3840PH30DBVR" (at 64.135 59.69 0)
      (effects (font (size 1.27 1.27) (thickness 0.15)) (justify left bottom) hide)
    )
    (property "Author" "Antmicro" (at 108.585 60.96 0)
      (effects (font (size 1.27 1.27) (thickness 0.15)) (justify left bottom) hide)
    )
    (property "License" "Apache-2.0" (at 108.585 63.5 0)
      (effects (font (size 1.27 1.27) (thickness 0.15)) (justify left bottom) hide)
    )
    (pin "1")
    (pin "2")
    (pin "3")
    (pin "4")
    (pin "5")
    (instances
      (project "kria-k26-devboard"
        (path ""
          (reference "U31") (unit 1)
        )
      )
    )
  )

  (symbol (lib_id "kria-k26-devboard:C_47n_0402") (at 67.31 52.705 270) (unit 1)
    (in_bom yes) (on_board yes) (dnp no) (fields_autoplaced)
    (property "Reference" "C131" (at 64.77 53.9813 90)
      (effects (font (size 1.524 1.524)) (justify right))
    )
    (property "Value" "C_47n_0402" (at 63.5 52.705 0)
      (effects (font (size 1.27 1.27) (thickness 0.15)) (justify left bottom) hide)
    )
    (property "Footprint" "kria-k26-devboard-footprints:C_0402_1005Metric" (at 72.39 57.785 0)
      (effects (font (size 1.27 1.27) (thickness 0.15)) (justify left bottom) hide)
    )
    (property "Datasheet" " " (at 67.31 52.705 0)
      (effects (font (size 1.27 1.27) (thickness 0.15)) (justify left bottom) hide)
    )
    (property "Manufacturer" "Multicomp" (at 77.47 57.785 0)
      (effects (font (size 1.27 1.27) (thickness 0.15)) (justify left bottom) hide)
    )
    (property "MPN" "MC0402X473K160CT" (at 74.93 57.785 0)
      (effects (font (size 1.27 1.27) (thickness 0.15)) (justify left bottom) hide)
    )
    (property "Val" "47n" (at 64.77 57.1562 90)
      (effects (font (size 1.27 1.27) (thickness 0.15)) (justify right))
    )
    (property "License" "Apache-2.0" (at 44.45 73.025 0)
      (effects (font (size 1.27 1.27) (thickness 0.15)) (justify left bottom) hide)
    )
    (property "Author" "Antmicro" (at 41.91 73.025 0)
      (effects (font (size 1.27 1.27) (thickness 0.15)) (justify left bottom) hide)
    )
    (property "Voltage" "" (at 39.37 73.025 0)
      (effects (font (size 1.27 1.27)) (justify left bottom) hide)
    )
    (property "Dielectric" "" (at 36.83 73.025 0)
      (effects (font (size 1.27 1.27)) (justify left bottom) hide)
    )
    (pin "1")
    (pin "2")
    (instances
      (project "kria-k26-devboard"
        (path ""
          (reference "C131") (unit 1)
        )
      )
    )
  )

  (symbol (lib_id "kria-k26-devboard:GND") (at 67.31 57.785 0) (unit 1)
    (in_bom yes) (on_board yes) (dnp no) (fields_autoplaced)
    (property "Reference" "#PWR0295" (at 67.31 64.135 0)
      (effects (font (size 1.27 1.27)) hide)
    )
    (property "Value" "GND" (at 67.31 62.865 0)
      (effects (font (size 1.27 1.27)))
    )
    (property "Footprint" "" (at 76.2 65.405 0)
      (effects (font (size 1.27 1.27) (thickness 0.15)) (justify left bottom) hide)
    )
    (property "Datasheet" "" (at 76.2 70.485 0)
      (effects (font (size 1.27 1.27) (thickness 0.15)) (justify left bottom) hide)
    )
    (property "Author" "Antmicro" (at 76.2 65.405 0)
      (effects (font (size 1.27 1.27) (thickness 0.15)) (justify left bottom) hide)
    )
    (property "License" "Apache-2.0" (at 76.2 67.945 0)
      (effects (font (size 1.27 1.27) (thickness 0.15)) (justify left bottom) hide)
    )
    (pin "1")
    (instances
      (project "kria-k26-devboard"
        (path ""
          (reference "#PWR0295") (unit 1)
        )
      )
    )
  )

  (symbol (lib_id "kria-k26-devboard:GND") (at 90.805 57.785 0) (unit 1)
    (in_bom yes) (on_board yes) (dnp no) (fields_autoplaced)
    (property "Reference" "#PWR0297" (at 90.805 64.135 0)
      (effects (font (size 1.27 1.27)) hide)
    )
    (property "Value" "GND" (at 90.805 62.865 0)
      (effects (font (size 1.27 1.27)))
    )
    (property "Footprint" "" (at 99.695 65.405 0)
      (effects (font (size 1.27 1.27) (thickness 0.15)) (justify left bottom) hide)
    )
    (property "Datasheet" "" (at 99.695 70.485 0)
      (effects (font (size 1.27 1.27) (thickness 0.15)) (justify left bottom) hide)
    )
    (property "Author" "Antmicro" (at 99.695 65.405 0)
      (effects (font (size 1.27 1.27) (thickness 0.15)) (justify left bottom) hide)
    )
    (property "License" "Apache-2.0" (at 99.695 67.945 0)
      (effects (font (size 1.27 1.27) (thickness 0.15)) (justify left bottom) hide)
    )
    (pin "1")
    (instances
      (project "kria-k26-devboard"
        (path ""
          (reference "#PWR0297") (unit 1)
        )
      )
    )
  )

  (symbol (lib_id "kria-k26-devboard:TPS3840PH30DBVR") (at 66.675 228.6 0) (unit 1)
    (in_bom yes) (on_board yes) (dnp no) (fields_autoplaced)
    (property "Reference" "U32" (at 76.2 219.71 0)
      (effects (font (size 1.524 1.524)))
    )
    (property "Value" "TPS3840PH30DBVR" (at 76.2 223.52 0)
      (effects (font (size 1.27 1.27) (thickness 0.15)) (justify left bottom))
    )
    (property "Footprint" "kria-k26-devboard-footprints:SOT-23-5" (at 57.785 241.3 0)
      (effects (font (size 1.27 1.27) (thickness 0.15)) (justify left bottom) hide)
    )
    (property "Datasheet" "https://www.ti.com/lit/ds/symlink/tps3840.pdf?HQS=dis-mous-null-mousermode-dsf-pf-null-wwe&DCM=yes&ref_url=https%3A%2F%2Fwww.mouser.com%2F&distId=26" (at 66.675 228.6 0)
      (effects (font (size 1.27 1.27) (thickness 0.15)) (justify left bottom) hide)
    )
    (property "Manufacturer" "Texas Instruments" (at 64.135 236.22 0)
      (effects (font (size 1.27 1.27) (thickness 0.15)) (justify left bottom) hide)
    )
    (property "MPN" "TPS3840PH30DBVR" (at 60.325 243.84 0)
      (effects (font (size 1.27 1.27) (thickness 0.15)) (justify left bottom) hide)
    )
    (property "Author" "Antmicro" (at 104.775 245.11 0)
      (effects (font (size 1.27 1.27) (thickness 0.15)) (justify left bottom) hide)
    )
    (property "License" "Apache-2.0" (at 104.775 247.65 0)
      (effects (font (size 1.27 1.27) (thickness 0.15)) (justify left bottom) hide)
    )
    (pin "1")
    (pin "2")
    (pin "3")
    (pin "4")
    (pin "5")
    (instances
      (project "kria-k26-devboard"
        (path ""
          (reference "U32") (unit 1)
        )
      )
    )
  )

  (symbol (lib_id "kria-k26-devboard:C_47n_0402") (at 58.42 237.49 270) (unit 1)
    (in_bom yes) (on_board yes) (dnp no) (fields_autoplaced)
    (property "Reference" "C130" (at 61.595 238.7663 90)
      (effects (font (size 1.524 1.524)) (justify left))
    )
    (property "Value" "C_47n_0402" (at 54.61 237.49 0)
      (effects (font (size 1.27 1.27) (thickness 0.15)) (justify left bottom) hide)
    )
    (property "Footprint" "kria-k26-devboard-footprints:C_0402_1005Metric" (at 63.5 242.57 0)
      (effects (font (size 1.27 1.27) (thickness 0.15)) (justify left bottom) hide)
    )
    (property "Datasheet" " " (at 58.42 237.49 0)
      (effects (font (size 1.27 1.27) (thickness 0.15)) (justify left bottom) hide)
    )
    (property "Manufacturer" "Multicomp" (at 68.58 242.57 0)
      (effects (font (size 1.27 1.27) (thickness 0.15)) (justify left bottom) hide)
    )
    (property "MPN" "MC0402X473K160CT" (at 66.04 242.57 0)
      (effects (font (size 1.27 1.27) (thickness 0.15)) (justify left bottom) hide)
    )
    (property "Val" "47n" (at 61.595 241.9412 90)
      (effects (font (size 1.27 1.27) (thickness 0.15)) (justify left))
    )
    (property "License" "Apache-2.0" (at 35.56 257.81 0)
      (effects (font (size 1.27 1.27) (thickness 0.15)) (justify left bottom) hide)
    )
    (property "Author" "Antmicro" (at 33.02 257.81 0)
      (effects (font (size 1.27 1.27) (thickness 0.15)) (justify left bottom) hide)
    )
    (property "Voltage" "" (at 30.48 257.81 0)
      (effects (font (size 1.27 1.27)) (justify left bottom) hide)
    )
    (property "Dielectric" "" (at 27.94 257.81 0)
      (effects (font (size 1.27 1.27)) (justify left bottom) hide)
    )
    (pin "1")
    (pin "2")
    (instances
      (project "kria-k26-devboard"
        (path ""
          (reference "C130") (unit 1)
        )
      )
    )
  )

  (symbol (lib_id "kria-k26-devboard:GND") (at 58.42 242.57 0) (unit 1)
    (in_bom yes) (on_board yes) (dnp no) (fields_autoplaced)
    (property "Reference" "#PWR0294" (at 58.42 248.92 0)
      (effects (font (size 1.27 1.27)) hide)
    )
    (property "Value" "GND" (at 58.42 247.65 0)
      (effects (font (size 1.27 1.27)))
    )
    (property "Footprint" "" (at 67.31 250.19 0)
      (effects (font (size 1.27 1.27) (thickness 0.15)) (justify left bottom) hide)
    )
    (property "Datasheet" "" (at 67.31 255.27 0)
      (effects (font (size 1.27 1.27) (thickness 0.15)) (justify left bottom) hide)
    )
    (property "Author" "Antmicro" (at 67.31 250.19 0)
      (effects (font (size 1.27 1.27) (thickness 0.15)) (justify left bottom) hide)
    )
    (property "License" "Apache-2.0" (at 67.31 252.73 0)
      (effects (font (size 1.27 1.27) (thickness 0.15)) (justify left bottom) hide)
    )
    (pin "1")
    (instances
      (project "kria-k26-devboard"
        (path ""
          (reference "#PWR0294") (unit 1)
        )
      )
    )
  )

  (symbol (lib_id "kria-k26-devboard:GND") (at 87.63 242.57 0) (unit 1)
    (in_bom yes) (on_board yes) (dnp no) (fields_autoplaced)
    (property "Reference" "#PWR0298" (at 87.63 248.92 0)
      (effects (font (size 1.27 1.27)) hide)
    )
    (property "Value" "GND" (at 87.63 247.65 0)
      (effects (font (size 1.27 1.27)))
    )
    (property "Footprint" "" (at 96.52 250.19 0)
      (effects (font (size 1.27 1.27) (thickness 0.15)) (justify left bottom) hide)
    )
    (property "Datasheet" "" (at 96.52 255.27 0)
      (effects (font (size 1.27 1.27) (thickness 0.15)) (justify left bottom) hide)
    )
    (property "Author" "Antmicro" (at 96.52 250.19 0)
      (effects (font (size 1.27 1.27) (thickness 0.15)) (justify left bottom) hide)
    )
    (property "License" "Apache-2.0" (at 96.52 252.73 0)
      (effects (font (size 1.27 1.27) (thickness 0.15)) (justify left bottom) hide)
    )
    (pin "1")
    (instances
      (project "kria-k26-devboard"
        (path ""
          (reference "#PWR0298") (unit 1)
        )
      )
    )
  )

  (symbol (lib_id "kria-k26-devboard:R_10k_0402") (at 311.15 44.45 270) (unit 1)
    (in_bom yes) (on_board yes) (dnp no)
    (property "Reference" "R92" (at 312.42 45.7201 90)
      (effects (font (size 1.524 1.524)) (justify left))
    )
    (property "Value" "R_10k_0402" (at 307.34 44.45 0)
      (effects (font (size 1.27 1.27) (thickness 0.15)) (justify left bottom) hide)
    )
    (property "Footprint" "kria-k26-devboard-footprints:R_0402_1005Metric" (at 316.23 49.53 0)
      (effects (font (size 1.27 1.27) (thickness 0.15)) (justify left bottom) hide)
    )
    (property "Datasheet" "https://www.bourns.com/docs/product-datasheets/cr.pdf" (at 311.15 44.45 0)
      (effects (font (size 1.27 1.27) (thickness 0.15)) (justify left bottom) hide)
    )
    (property "Manufacturer" "Bourns" (at 321.31 49.53 0)
      (effects (font (size 1.27 1.27) (thickness 0.15)) (justify left bottom) hide)
    )
    (property "MPN" "CR0402-FX-1002GLF" (at 318.77 49.53 0)
      (effects (font (size 1.27 1.27) (thickness 0.15)) (justify left bottom) hide)
    )
    (property "Val" "10k" (at 312.42 48.26 90)
      (effects (font (size 1.27 1.27) (thickness 0.15)) (justify left))
    )
    (property "License" "Apache-2.0" (at 285.75 64.77 0)
      (effects (font (size 1.27 1.27) (thickness 0.15)) (justify left bottom) hide)
    )
    (property "Author" "Antmicro" (at 283.21 64.77 0)
      (effects (font (size 1.27 1.27) (thickness 0.15)) (justify left bottom) hide)
    )
    (property "Tolerance" "1%" (at 300.99 64.77 0)
      (effects (font (size 1.27 1.27)) (justify left bottom) hide)
    )
    (pin "1")
    (pin "2")
    (instances
      (project "kria-k26-devboard"
        (path ""
          (reference "R92") (unit 1)
        )
      )
    )
  )

  (symbol (lib_id "kria-k26-devboard:R_10k_0402") (at 334.01 44.45 270) (unit 1)
    (in_bom yes) (on_board yes) (dnp no)
    (property "Reference" "R94" (at 335.28 45.7201 90)
      (effects (font (size 1.524 1.524)) (justify left))
    )
    (property "Value" "R_10k_0402" (at 330.2 44.45 0)
      (effects (font (size 1.27 1.27) (thickness 0.15)) (justify left bottom) hide)
    )
    (property "Footprint" "kria-k26-devboard-footprints:R_0402_1005Metric" (at 339.09 49.53 0)
      (effects (font (size 1.27 1.27) (thickness 0.15)) (justify left bottom) hide)
    )
    (property "Datasheet" "https://www.bourns.com/docs/product-datasheets/cr.pdf" (at 334.01 44.45 0)
      (effects (font (size 1.27 1.27) (thickness 0.15)) (justify left bottom) hide)
    )
    (property "Manufacturer" "Bourns" (at 344.17 49.53 0)
      (effects (font (size 1.27 1.27) (thickness 0.15)) (justify left bottom) hide)
    )
    (property "MPN" "CR0402-FX-1002GLF" (at 341.63 49.53 0)
      (effects (font (size 1.27 1.27) (thickness 0.15)) (justify left bottom) hide)
    )
    (property "Val" "10k" (at 335.28 48.26 90)
      (effects (font (size 1.27 1.27) (thickness 0.15)) (justify left))
    )
    (property "License" "Apache-2.0" (at 308.61 64.77 0)
      (effects (font (size 1.27 1.27) (thickness 0.15)) (justify left bottom) hide)
    )
    (property "Author" "Antmicro" (at 306.07 64.77 0)
      (effects (font (size 1.27 1.27) (thickness 0.15)) (justify left bottom) hide)
    )
    (property "Tolerance" "1%" (at 323.85 64.77 0)
      (effects (font (size 1.27 1.27)) (justify left bottom) hide)
    )
    (pin "1")
    (pin "2")
    (instances
      (project "kria-k26-devboard"
        (path ""
          (reference "R94") (unit 1)
        )
      )
    )
  )

  (symbol (lib_id "kria-k26-devboard:R_10k_0402") (at 318.77 44.45 270) (unit 1)
    (in_bom yes) (on_board yes) (dnp no)
    (property "Reference" "R95" (at 320.04 45.7201 90)
      (effects (font (size 1.524 1.524)) (justify left))
    )
    (property "Value" "R_10k_0402" (at 314.96 44.45 0)
      (effects (font (size 1.27 1.27) (thickness 0.15)) (justify left bottom) hide)
    )
    (property "Footprint" "kria-k26-devboard-footprints:R_0402_1005Metric" (at 323.85 49.53 0)
      (effects (font (size 1.27 1.27) (thickness 0.15)) (justify left bottom) hide)
    )
    (property "Datasheet" "https://www.bourns.com/docs/product-datasheets/cr.pdf" (at 318.77 44.45 0)
      (effects (font (size 1.27 1.27) (thickness 0.15)) (justify left bottom) hide)
    )
    (property "Manufacturer" "Bourns" (at 328.93 49.53 0)
      (effects (font (size 1.27 1.27) (thickness 0.15)) (justify left bottom) hide)
    )
    (property "MPN" "CR0402-FX-1002GLF" (at 326.39 49.53 0)
      (effects (font (size 1.27 1.27) (thickness 0.15)) (justify left bottom) hide)
    )
    (property "Val" "10k" (at 320.04 48.26 90)
      (effects (font (size 1.27 1.27) (thickness 0.15)) (justify left))
    )
    (property "License" "Apache-2.0" (at 293.37 64.77 0)
      (effects (font (size 1.27 1.27) (thickness 0.15)) (justify left bottom) hide)
    )
    (property "Author" "Antmicro" (at 290.83 64.77 0)
      (effects (font (size 1.27 1.27) (thickness 0.15)) (justify left bottom) hide)
    )
    (property "Tolerance" "1%" (at 308.61 64.77 0)
      (effects (font (size 1.27 1.27)) (justify left bottom) hide)
    )
    (pin "1")
    (pin "2")
    (instances
      (project "kria-k26-devboard"
        (path ""
          (reference "R95") (unit 1)
        )
      )
    )
  )

  (symbol (lib_id "kria-k26-devboard:R_10k_0402") (at 341.63 44.45 270) (unit 1)
    (in_bom yes) (on_board yes) (dnp no)
    (property "Reference" "R96" (at 342.9 45.7201 90)
      (effects (font (size 1.524 1.524)) (justify left))
    )
    (property "Value" "R_10k_0402" (at 337.82 44.45 0)
      (effects (font (size 1.27 1.27) (thickness 0.15)) (justify left bottom) hide)
    )
    (property "Footprint" "kria-k26-devboard-footprints:R_0402_1005Metric" (at 346.71 49.53 0)
      (effects (font (size 1.27 1.27) (thickness 0.15)) (justify left bottom) hide)
    )
    (property "Datasheet" "https://www.bourns.com/docs/product-datasheets/cr.pdf" (at 341.63 44.45 0)
      (effects (font (size 1.27 1.27) (thickness 0.15)) (justify left bottom) hide)
    )
    (property "Manufacturer" "Bourns" (at 351.79 49.53 0)
      (effects (font (size 1.27 1.27) (thickness 0.15)) (justify left bottom) hide)
    )
    (property "MPN" "CR0402-FX-1002GLF" (at 349.25 49.53 0)
      (effects (font (size 1.27 1.27) (thickness 0.15)) (justify left bottom) hide)
    )
    (property "Val" "10k" (at 342.9 48.26 90)
      (effects (font (size 1.27 1.27) (thickness 0.15)) (justify left))
    )
    (property "License" "Apache-2.0" (at 316.23 64.77 0)
      (effects (font (size 1.27 1.27) (thickness 0.15)) (justify left bottom) hide)
    )
    (property "Author" "Antmicro" (at 313.69 64.77 0)
      (effects (font (size 1.27 1.27) (thickness 0.15)) (justify left bottom) hide)
    )
    (property "Tolerance" "1%" (at 331.47 64.77 0)
      (effects (font (size 1.27 1.27)) (justify left bottom) hide)
    )
    (pin "1")
    (pin "2")
    (instances
      (project "kria-k26-devboard"
        (path ""
          (reference "R96") (unit 1)
        )
      )
    )
  )

  (symbol (lib_id "kria-k26-devboard:GND") (at 175.895 45.085 0) (unit 1)
    (in_bom yes) (on_board yes) (dnp no) (fields_autoplaced)
    (property "Reference" "#PWR0306" (at 175.895 51.435 0)
      (effects (font (size 1.27 1.27)) hide)
    )
    (property "Value" "GND" (at 175.895 50.165 0)
      (effects (font (size 1.27 1.27)))
    )
    (property "Footprint" "" (at 184.785 52.705 0)
      (effects (font (size 1.27 1.27) (thickness 0.15)) (justify left bottom) hide)
    )
    (property "Datasheet" "" (at 184.785 57.785 0)
      (effects (font (size 1.27 1.27) (thickness 0.15)) (justify left bottom) hide)
    )
    (property "Author" "Antmicro" (at 184.785 52.705 0)
      (effects (font (size 1.27 1.27) (thickness 0.15)) (justify left bottom) hide)
    )
    (property "License" "Apache-2.0" (at 184.785 55.245 0)
      (effects (font (size 1.27 1.27) (thickness 0.15)) (justify left bottom) hide)
    )
    (pin "1")
    (instances
      (project "kria-k26-devboard"
        (path ""
          (reference "#PWR0306") (unit 1)
        )
      )
    )
  )

  (symbol (lib_id "kria-k26-devboard:GND") (at 304.165 146.685 0) (unit 1)
    (in_bom yes) (on_board yes) (dnp no) (fields_autoplaced)
    (property "Reference" "#PWR0317" (at 304.165 153.035 0)
      (effects (font (size 1.27 1.27)) hide)
    )
    (property "Value" "GND" (at 304.165 151.765 0)
      (effects (font (size 1.27 1.27)))
    )
    (property "Footprint" "" (at 313.055 154.305 0)
      (effects (font (size 1.27 1.27) (thickness 0.15)) (justify left bottom) hide)
    )
    (property "Datasheet" "" (at 313.055 159.385 0)
      (effects (font (size 1.27 1.27) (thickness 0.15)) (justify left bottom) hide)
    )
    (property "Author" "Antmicro" (at 313.055 154.305 0)
      (effects (font (size 1.27 1.27) (thickness 0.15)) (justify left bottom) hide)
    )
    (property "License" "Apache-2.0" (at 313.055 156.845 0)
      (effects (font (size 1.27 1.27) (thickness 0.15)) (justify left bottom) hide)
    )
    (pin "1")
    (instances
      (project "kria-k26-devboard"
        (path ""
          (reference "#PWR0317") (unit 1)
        )
      )
    )
  )

  (symbol (lib_id "kria-k26-devboard:GND") (at 200.66 49.53 0) (unit 1)
    (in_bom yes) (on_board yes) (dnp no) (fields_autoplaced)
    (property "Reference" "#PWR0308" (at 200.66 55.88 0)
      (effects (font (size 1.27 1.27)) hide)
    )
    (property "Value" "GND" (at 203.2 50.7999 0)
      (effects (font (size 1.27 1.27)) (justify left))
    )
    (property "Footprint" "" (at 209.55 57.15 0)
      (effects (font (size 1.27 1.27) (thickness 0.15)) (justify left bottom) hide)
    )
    (property "Datasheet" "" (at 209.55 62.23 0)
      (effects (font (size 1.27 1.27) (thickness 0.15)) (justify left bottom) hide)
    )
    (property "Author" "Antmicro" (at 209.55 57.15 0)
      (effects (font (size 1.27 1.27) (thickness 0.15)) (justify left bottom) hide)
    )
    (property "License" "Apache-2.0" (at 209.55 59.69 0)
      (effects (font (size 1.27 1.27) (thickness 0.15)) (justify left bottom) hide)
    )
    (pin "1")
    (instances
      (project "kria-k26-devboard"
        (path ""
          (reference "#PWR0308") (unit 1)
        )
      )
    )
  )

  (symbol (lib_id "kria-k26-devboard:C_100n_0402") (at 151.765 40.005 270) (unit 1)
    (in_bom yes) (on_board yes) (dnp no)
    (property "Reference" "C134" (at 154.305 41.2813 90)
      (effects (font (size 1.524 1.524)) (justify left))
    )
    (property "Value" "C_100n_0402" (at 147.955 40.005 0)
      (effects (font (size 1.27 1.27) (thickness 0.15)) (justify left bottom) hide)
    )
    (property "Footprint" "kria-k26-devboard-footprints:C_0402_1005Metric" (at 156.845 45.085 0)
      (effects (font (size 1.27 1.27) (thickness 0.15)) (justify left bottom) hide)
    )
    (property "Datasheet" "https://search.murata.co.jp/Ceramy/image/img/A01X/G101/ENG/GRM155R61H104KE14-01.pdf" (at 151.765 40.005 0)
      (effects (font (size 1.27 1.27) (thickness 0.15)) (justify left bottom) hide)
    )
    (property "Manufacturer" "Murata" (at 161.925 45.085 0)
      (effects (font (size 1.27 1.27) (thickness 0.15)) (justify left bottom) hide)
    )
    (property "MPN" "GRM155R61H104KE14D" (at 159.385 45.085 0)
      (effects (font (size 1.27 1.27) (thickness 0.15)) (justify left bottom) hide)
    )
    (property "Val" "100n" (at 154.305 44.4562 90)
      (effects (font (size 1.27 1.27) (thickness 0.15)) (justify left))
    )
    (property "License" "Apache-2.0" (at 128.905 60.325 0)
      (effects (font (size 1.27 1.27) (thickness 0.15)) (justify left bottom) hide)
    )
    (property "Author" "Antmicro" (at 126.365 60.325 0)
      (effects (font (size 1.27 1.27) (thickness 0.15)) (justify left bottom) hide)
    )
    (property "Voltage" "50V" (at 123.825 60.325 0)
      (effects (font (size 1.27 1.27)) (justify left bottom) hide)
    )
    (property "Dielectric" "X5R" (at 121.285 60.325 0)
      (effects (font (size 1.27 1.27)) (justify left bottom) hide)
    )
    (pin "1")
    (pin "2")
    (instances
      (project "kria-k26-devboard"
        (path ""
          (reference "C134") (unit 1)
        )
      )
    )
  )

  (symbol (lib_id "kria-k26-devboard:GND") (at 151.765 45.085 0) (unit 1)
    (in_bom yes) (on_board yes) (dnp no) (fields_autoplaced)
    (property "Reference" "#PWR0302" (at 151.765 51.435 0)
      (effects (font (size 1.27 1.27)) hide)
    )
    (property "Value" "GND" (at 151.765 50.419 0)
      (effects (font (size 1.27 1.27)))
    )
    (property "Footprint" "" (at 160.655 52.705 0)
      (effects (font (size 1.27 1.27) (thickness 0.15)) (justify left bottom) hide)
    )
    (property "Datasheet" "" (at 160.655 57.785 0)
      (effects (font (size 1.27 1.27) (thickness 0.15)) (justify left bottom) hide)
    )
    (property "Author" "Antmicro" (at 160.655 52.705 0)
      (effects (font (size 1.27 1.27) (thickness 0.15)) (justify left bottom) hide)
    )
    (property "License" "Apache-2.0" (at 160.655 55.245 0)
      (effects (font (size 1.27 1.27) (thickness 0.15)) (justify left bottom) hide)
    )
    (pin "1")
    (instances
      (project "kria-k26-devboard"
        (path ""
          (reference "#PWR0302") (unit 1)
        )
      )
    )
  )

  (symbol (lib_id "kria-k26-devboard:C_100n_0402") (at 151.765 54.61 270) (unit 1)
    (in_bom yes) (on_board yes) (dnp no) (fields_autoplaced)
    (property "Reference" "C136" (at 154.94 55.8863 90)
      (effects (font (size 1.524 1.524)) (justify left))
    )
    (property "Value" "C_100n_0402" (at 147.955 54.61 0)
      (effects (font (size 1.27 1.27) (thickness 0.15)) (justify left bottom) hide)
    )
    (property "Footprint" "kria-k26-devboard-footprints:C_0402_1005Metric" (at 156.845 59.69 0)
      (effects (font (size 1.27 1.27) (thickness 0.15)) (justify left bottom) hide)
    )
    (property "Datasheet" "https://search.murata.co.jp/Ceramy/image/img/A01X/G101/ENG/GRM155R61H104KE14-01.pdf" (at 151.765 54.61 0)
      (effects (font (size 1.27 1.27) (thickness 0.15)) (justify left bottom) hide)
    )
    (property "Manufacturer" "Murata" (at 161.925 59.69 0)
      (effects (font (size 1.27 1.27) (thickness 0.15)) (justify left bottom) hide)
    )
    (property "MPN" "GRM155R61H104KE14D" (at 159.385 59.69 0)
      (effects (font (size 1.27 1.27) (thickness 0.15)) (justify left bottom) hide)
    )
    (property "Val" "100n" (at 154.94 59.0612 90)
      (effects (font (size 1.27 1.27) (thickness 0.15)) (justify left))
    )
    (property "License" "Apache-2.0" (at 128.905 74.93 0)
      (effects (font (size 1.27 1.27) (thickness 0.15)) (justify left bottom) hide)
    )
    (property "Author" "Antmicro" (at 126.365 74.93 0)
      (effects (font (size 1.27 1.27) (thickness 0.15)) (justify left bottom) hide)
    )
    (property "Voltage" "50V" (at 123.825 74.93 0)
      (effects (font (size 1.27 1.27)) (justify left bottom) hide)
    )
    (property "Dielectric" "X5R" (at 121.285 74.93 0)
      (effects (font (size 1.27 1.27)) (justify left bottom) hide)
    )
    (pin "1")
    (pin "2")
    (instances
      (project "kria-k26-devboard"
        (path ""
          (reference "C136") (unit 1)
        )
      )
    )
  )

  (symbol (lib_id "kria-k26-devboard:GND") (at 151.765 59.69 0) (unit 1)
    (in_bom yes) (on_board yes) (dnp no) (fields_autoplaced)
    (property "Reference" "#PWR0305" (at 151.765 66.04 0)
      (effects (font (size 1.27 1.27)) hide)
    )
    (property "Value" "GND" (at 151.765 65.024 0)
      (effects (font (size 1.27 1.27)))
    )
    (property "Footprint" "" (at 160.655 67.31 0)
      (effects (font (size 1.27 1.27) (thickness 0.15)) (justify left bottom) hide)
    )
    (property "Datasheet" "" (at 160.655 72.39 0)
      (effects (font (size 1.27 1.27) (thickness 0.15)) (justify left bottom) hide)
    )
    (property "Author" "Antmicro" (at 160.655 67.31 0)
      (effects (font (size 1.27 1.27) (thickness 0.15)) (justify left bottom) hide)
    )
    (property "License" "Apache-2.0" (at 160.655 69.85 0)
      (effects (font (size 1.27 1.27) (thickness 0.15)) (justify left bottom) hide)
    )
    (pin "1")
    (instances
      (project "kria-k26-devboard"
        (path ""
          (reference "#PWR0305") (unit 1)
        )
      )
    )
  )

  (symbol (lib_id "kria-k26-devboard:C_100n_0402") (at 108.585 54.61 270) (unit 1)
    (in_bom yes) (on_board yes) (dnp no) (fields_autoplaced)
    (property "Reference" "C132" (at 111.125 55.8863 90)
      (effects (font (size 1.524 1.524)) (justify left))
    )
    (property "Value" "C_100n_0402" (at 104.775 54.61 0)
      (effects (font (size 1.27 1.27) (thickness 0.15)) (justify left bottom) hide)
    )
    (property "Footprint" "kria-k26-devboard-footprints:C_0402_1005Metric" (at 113.665 59.69 0)
      (effects (font (size 1.27 1.27) (thickness 0.15)) (justify left bottom) hide)
    )
    (property "Datasheet" "https://search.murata.co.jp/Ceramy/image/img/A01X/G101/ENG/GRM155R61H104KE14-01.pdf" (at 108.585 54.61 0)
      (effects (font (size 1.27 1.27) (thickness 0.15)) (justify left bottom) hide)
    )
    (property "Manufacturer" "Murata" (at 118.745 59.69 0)
      (effects (font (size 1.27 1.27) (thickness 0.15)) (justify left bottom) hide)
    )
    (property "MPN" "GRM155R61H104KE14D" (at 116.205 59.69 0)
      (effects (font (size 1.27 1.27) (thickness 0.15)) (justify left bottom) hide)
    )
    (property "Val" "100n" (at 111.125 59.0612 90)
      (effects (font (size 1.27 1.27) (thickness 0.15)) (justify left))
    )
    (property "License" "Apache-2.0" (at 85.725 74.93 0)
      (effects (font (size 1.27 1.27) (thickness 0.15)) (justify left bottom) hide)
    )
    (property "Author" "Antmicro" (at 83.185 74.93 0)
      (effects (font (size 1.27 1.27) (thickness 0.15)) (justify left bottom) hide)
    )
    (property "Voltage" "50V" (at 80.645 74.93 0)
      (effects (font (size 1.27 1.27)) (justify left bottom) hide)
    )
    (property "Dielectric" "X5R" (at 78.105 74.93 0)
      (effects (font (size 1.27 1.27)) (justify left bottom) hide)
    )
    (pin "1")
    (pin "2")
    (instances
      (project "kria-k26-devboard"
        (path ""
          (reference "C132") (unit 1)
        )
      )
    )
  )

  (symbol (lib_id "kria-k26-devboard:GND") (at 108.585 59.69 0) (unit 1)
    (in_bom yes) (on_board yes) (dnp no) (fields_autoplaced)
    (property "Reference" "#PWR0299" (at 108.585 66.04 0)
      (effects (font (size 1.27 1.27)) hide)
    )
    (property "Value" "GND" (at 108.585 64.77 0)
      (effects (font (size 1.27 1.27)))
    )
    (property "Footprint" "" (at 117.475 67.31 0)
      (effects (font (size 1.27 1.27) (thickness 0.15)) (justify left bottom) hide)
    )
    (property "Datasheet" "" (at 117.475 72.39 0)
      (effects (font (size 1.27 1.27) (thickness 0.15)) (justify left bottom) hide)
    )
    (property "Author" "Antmicro" (at 117.475 67.31 0)
      (effects (font (size 1.27 1.27) (thickness 0.15)) (justify left bottom) hide)
    )
    (property "License" "Apache-2.0" (at 117.475 69.85 0)
      (effects (font (size 1.27 1.27) (thickness 0.15)) (justify left bottom) hide)
    )
    (pin "1")
    (instances
      (project "kria-k26-devboard"
        (path ""
          (reference "#PWR0299") (unit 1)
        )
      )
    )
  )

  (symbol (lib_id "kria-k26-devboard:C_100n_0402") (at 172.72 195.58 270) (unit 1)
    (in_bom yes) (on_board yes) (dnp no) (fields_autoplaced)
    (property "Reference" "C135" (at 175.895 196.8563 90)
      (effects (font (size 1.524 1.524)) (justify left))
    )
    (property "Value" "C_100n_0402" (at 168.91 195.58 0)
      (effects (font (size 1.27 1.27) (thickness 0.15)) (justify left bottom) hide)
    )
    (property "Footprint" "kria-k26-devboard-footprints:C_0402_1005Metric" (at 177.8 200.66 0)
      (effects (font (size 1.27 1.27) (thickness 0.15)) (justify left bottom) hide)
    )
    (property "Datasheet" "https://search.murata.co.jp/Ceramy/image/img/A01X/G101/ENG/GRM155R61H104KE14-01.pdf" (at 172.72 195.58 0)
      (effects (font (size 1.27 1.27) (thickness 0.15)) (justify left bottom) hide)
    )
    (property "Manufacturer" "Murata" (at 182.88 200.66 0)
      (effects (font (size 1.27 1.27) (thickness 0.15)) (justify left bottom) hide)
    )
    (property "MPN" "GRM155R61H104KE14D" (at 180.34 200.66 0)
      (effects (font (size 1.27 1.27) (thickness 0.15)) (justify left bottom) hide)
    )
    (property "Val" "100n" (at 175.895 200.0312 90)
      (effects (font (size 1.27 1.27) (thickness 0.15)) (justify left))
    )
    (property "License" "Apache-2.0" (at 149.86 215.9 0)
      (effects (font (size 1.27 1.27) (thickness 0.15)) (justify left bottom) hide)
    )
    (property "Author" "Antmicro" (at 147.32 215.9 0)
      (effects (font (size 1.27 1.27) (thickness 0.15)) (justify left bottom) hide)
    )
    (property "Voltage" "50V" (at 144.78 215.9 0)
      (effects (font (size 1.27 1.27)) (justify left bottom) hide)
    )
    (property "Dielectric" "X5R" (at 142.24 215.9 0)
      (effects (font (size 1.27 1.27)) (justify left bottom) hide)
    )
    (pin "1")
    (pin "2")
    (instances
      (project "kria-k26-devboard"
        (path ""
          (reference "C135") (unit 1)
        )
      )
    )
  )

  (symbol (lib_id "kria-k26-devboard:GND") (at 172.72 200.66 0) (unit 1)
    (in_bom yes) (on_board yes) (dnp no) (fields_autoplaced)
    (property "Reference" "#PWR0304" (at 172.72 207.01 0)
      (effects (font (size 1.27 1.27)) hide)
    )
    (property "Value" "GND" (at 172.72 205.74 0)
      (effects (font (size 1.27 1.27)))
    )
    (property "Footprint" "" (at 181.61 208.28 0)
      (effects (font (size 1.27 1.27) (thickness 0.15)) (justify left bottom) hide)
    )
    (property "Datasheet" "" (at 181.61 213.36 0)
      (effects (font (size 1.27 1.27) (thickness 0.15)) (justify left bottom) hide)
    )
    (property "Author" "Antmicro" (at 181.61 208.28 0)
      (effects (font (size 1.27 1.27) (thickness 0.15)) (justify left bottom) hide)
    )
    (property "License" "Apache-2.0" (at 181.61 210.82 0)
      (effects (font (size 1.27 1.27) (thickness 0.15)) (justify left bottom) hide)
    )
    (pin "1")
    (instances
      (project "kria-k26-devboard"
        (path ""
          (reference "#PWR0304") (unit 1)
        )
      )
    )
  )

  (symbol (lib_id "kria-k26-devboard:C_100n_0402") (at 112.395 237.49 270) (unit 1)
    (in_bom yes) (on_board yes) (dnp no) (fields_autoplaced)
    (property "Reference" "C133" (at 115.57 238.7663 90)
      (effects (font (size 1.524 1.524)) (justify left))
    )
    (property "Value" "C_100n_0402" (at 108.585 237.49 0)
      (effects (font (size 1.27 1.27) (thickness 0.15)) (justify left bottom) hide)
    )
    (property "Footprint" "kria-k26-devboard-footprints:C_0402_1005Metric" (at 117.475 242.57 0)
      (effects (font (size 1.27 1.27) (thickness 0.15)) (justify left bottom) hide)
    )
    (property "Datasheet" "https://search.murata.co.jp/Ceramy/image/img/A01X/G101/ENG/GRM155R61H104KE14-01.pdf" (at 112.395 237.49 0)
      (effects (font (size 1.27 1.27) (thickness 0.15)) (justify left bottom) hide)
    )
    (property "Manufacturer" "Murata" (at 122.555 242.57 0)
      (effects (font (size 1.27 1.27) (thickness 0.15)) (justify left bottom) hide)
    )
    (property "MPN" "GRM155R61H104KE14D" (at 120.015 242.57 0)
      (effects (font (size 1.27 1.27) (thickness 0.15)) (justify left bottom) hide)
    )
    (property "Val" "100n" (at 115.57 241.9412 90)
      (effects (font (size 1.27 1.27) (thickness 0.15)) (justify left))
    )
    (property "License" "Apache-2.0" (at 89.535 257.81 0)
      (effects (font (size 1.27 1.27) (thickness 0.15)) (justify left bottom) hide)
    )
    (property "Author" "Antmicro" (at 86.995 257.81 0)
      (effects (font (size 1.27 1.27) (thickness 0.15)) (justify left bottom) hide)
    )
    (property "Voltage" "50V" (at 84.455 257.81 0)
      (effects (font (size 1.27 1.27)) (justify left bottom) hide)
    )
    (property "Dielectric" "X5R" (at 81.915 257.81 0)
      (effects (font (size 1.27 1.27)) (justify left bottom) hide)
    )
    (pin "1")
    (pin "2")
    (instances
      (project "kria-k26-devboard"
        (path ""
          (reference "C133") (unit 1)
        )
      )
    )
  )

  (symbol (lib_id "kria-k26-devboard:GND") (at 112.395 242.57 0) (unit 1)
    (in_bom yes) (on_board yes) (dnp no) (fields_autoplaced)
    (property "Reference" "#PWR0301" (at 112.395 248.92 0)
      (effects (font (size 1.27 1.27)) hide)
    )
    (property "Value" "GND" (at 112.395 247.65 0)
      (effects (font (size 1.27 1.27)))
    )
    (property "Footprint" "" (at 121.285 250.19 0)
      (effects (font (size 1.27 1.27) (thickness 0.15)) (justify left bottom) hide)
    )
    (property "Datasheet" "" (at 121.285 255.27 0)
      (effects (font (size 1.27 1.27) (thickness 0.15)) (justify left bottom) hide)
    )
    (property "Author" "Antmicro" (at 121.285 250.19 0)
      (effects (font (size 1.27 1.27) (thickness 0.15)) (justify left bottom) hide)
    )
    (property "License" "Apache-2.0" (at 121.285 252.73 0)
      (effects (font (size 1.27 1.27) (thickness 0.15)) (justify left bottom) hide)
    )
    (pin "1")
    (instances
      (project "kria-k26-devboard"
        (path ""
          (reference "#PWR0301") (unit 1)
        )
      )
    )
  )

  (symbol (lib_id "kria-k26-devboard:C_100n_0402") (at 292.735 139.065 270) (unit 1)
    (in_bom yes) (on_board yes) (dnp no) (fields_autoplaced)
    (property "Reference" "C139" (at 295.275 140.3413 90)
      (effects (font (size 1.524 1.524)) (justify left))
    )
    (property "Value" "C_100n_0402" (at 288.925 139.065 0)
      (effects (font (size 1.27 1.27) (thickness 0.15)) (justify left bottom) hide)
    )
    (property "Footprint" "kria-k26-devboard-footprints:C_0402_1005Metric" (at 297.815 144.145 0)
      (effects (font (size 1.27 1.27) (thickness 0.15)) (justify left bottom) hide)
    )
    (property "Datasheet" "https://search.murata.co.jp/Ceramy/image/img/A01X/G101/ENG/GRM155R61H104KE14-01.pdf" (at 292.735 139.065 0)
      (effects (font (size 1.27 1.27) (thickness 0.15)) (justify left bottom) hide)
    )
    (property "Manufacturer" "Murata" (at 302.895 144.145 0)
      (effects (font (size 1.27 1.27) (thickness 0.15)) (justify left bottom) hide)
    )
    (property "MPN" "GRM155R61H104KE14D" (at 300.355 144.145 0)
      (effects (font (size 1.27 1.27) (thickness 0.15)) (justify left bottom) hide)
    )
    (property "Val" "100n" (at 295.275 143.5162 90)
      (effects (font (size 1.27 1.27) (thickness 0.15)) (justify left))
    )
    (property "License" "Apache-2.0" (at 269.875 159.385 0)
      (effects (font (size 1.27 1.27) (thickness 0.15)) (justify left bottom) hide)
    )
    (property "Author" "Antmicro" (at 267.335 159.385 0)
      (effects (font (size 1.27 1.27) (thickness 0.15)) (justify left bottom) hide)
    )
    (property "Voltage" "50V" (at 264.795 159.385 0)
      (effects (font (size 1.27 1.27)) (justify left bottom) hide)
    )
    (property "Dielectric" "X5R" (at 262.255 159.385 0)
      (effects (font (size 1.27 1.27)) (justify left bottom) hide)
    )
    (pin "1")
    (pin "2")
    (instances
      (project "kria-k26-devboard"
        (path ""
          (reference "C139") (unit 1)
        )
      )
    )
  )

  (symbol (lib_id "kria-k26-devboard:1N4148WS") (at 56.515 48.26 180) (unit 1)
    (in_bom yes) (on_board yes) (dnp no) (fields_autoplaced)
    (property "Reference" "D5" (at 52.705 40.64 0)
      (effects (font (size 1.524 1.524)))
    )
    (property "Value" "1N4148WS" (at 52.705 44.45 0)
      (effects (font (size 1.27 1.27) (thickness 0.15)))
    )
    (property "Footprint" "kria-k26-devboard-footprints:D_SOD-323F" (at 51.435 53.34 0)
      (effects (font (size 1.27 1.27) (thickness 0.15)) (justify left bottom) hide)
    )
    (property "Datasheet" "https://www.onsemi.com/pub/Collateral/1N914BWS-D.pdf" (at 51.435 55.88 0)
      (effects (font (size 1.27 1.27) (thickness 0.15)) (justify left bottom) hide)
    )
    (property "MPN" "1N4148WS" (at 51.435 60.96 0)
      (effects (font (size 1.27 1.27) (thickness 0.15)) (justify left bottom) hide)
    )
    (property "Manufacturer" "ON Semiconductor" (at 51.435 76.2 0)
      (effects (font (size 1.27 1.27) (thickness 0.15)) (justify left bottom) hide)
    )
    (property "Author" "Antmicro" (at 34.925 27.94 0)
      (effects (font (size 1.27 1.27) (thickness 0.15)) (justify left bottom) hide)
    )
    (property "License" "Apache-2.0" (at 34.925 25.4 0)
      (effects (font (size 1.27 1.27) (thickness 0.15)) (justify left bottom) hide)
    )
    (pin "A")
    (pin "K")
    (instances
      (project "kria-k26-devboard"
        (path ""
          (reference "D5") (unit 1)
        )
      )
    )
  )

  (symbol (lib_id "kria-k26-devboard:1N4148WS") (at 53.975 232.41 180) (unit 1)
    (in_bom yes) (on_board yes) (dnp no) (fields_autoplaced)
    (property "Reference" "D4" (at 50.165 237.49 0)
      (effects (font (size 1.524 1.524)))
    )
    (property "Value" "1N4148WS" (at 50.165 240.03 0)
      (effects (font (size 1.27 1.27) (thickness 0.15)))
    )
    (property "Footprint" "kria-k26-devboard-footprints:D_SOD-323F" (at 48.895 237.49 0)
      (effects (font (size 1.27 1.27) (thickness 0.15)) (justify left bottom) hide)
    )
    (property "Datasheet" "https://www.onsemi.com/pub/Collateral/1N914BWS-D.pdf" (at 48.895 240.03 0)
      (effects (font (size 1.27 1.27) (thickness 0.15)) (justify left bottom) hide)
    )
    (property "MPN" "1N4148WS" (at 48.895 245.11 0)
      (effects (font (size 1.27 1.27) (thickness 0.15)) (justify left bottom) hide)
    )
    (property "Manufacturer" "ON Semiconductor" (at 48.895 260.35 0)
      (effects (font (size 1.27 1.27) (thickness 0.15)) (justify left bottom) hide)
    )
    (property "Author" "Antmicro" (at 32.385 212.09 0)
      (effects (font (size 1.27 1.27) (thickness 0.15)) (justify left bottom) hide)
    )
    (property "License" "Apache-2.0" (at 32.385 209.55 0)
      (effects (font (size 1.27 1.27) (thickness 0.15)) (justify left bottom) hide)
    )
    (pin "A")
    (pin "K")
    (instances
      (project "kria-k26-devboard"
        (path ""
          (reference "D4") (unit 1)
        )
      )
    )
  )

  (symbol (lib_id "kria-k26-devboard:GND") (at 213.995 67.945 0) (unit 1)
    (in_bom yes) (on_board yes) (dnp no) (fields_autoplaced)
    (property "Reference" "#PWR0312" (at 213.995 74.295 0)
      (effects (font (size 1.27 1.27)) hide)
    )
    (property "Value" "GND" (at 213.995 73.025 0)
      (effects (font (size 1.27 1.27)))
    )
    (property "Footprint" "" (at 222.885 75.565 0)
      (effects (font (size 1.27 1.27) (thickness 0.15)) (justify left bottom) hide)
    )
    (property "Datasheet" "" (at 222.885 80.645 0)
      (effects (font (size 1.27 1.27) (thickness 0.15)) (justify left bottom) hide)
    )
    (property "Author" "Antmicro" (at 222.885 75.565 0)
      (effects (font (size 1.27 1.27) (thickness 0.15)) (justify left bottom) hide)
    )
    (property "License" "Apache-2.0" (at 222.885 78.105 0)
      (effects (font (size 1.27 1.27) (thickness 0.15)) (justify left bottom) hide)
    )
    (pin "1")
    (instances
      (project "kria-k26-devboard"
        (path ""
          (reference "#PWR0312") (unit 1)
        )
      )
    )
  )

  (symbol (lib_id "kria-k26-devboard:GND") (at 221.615 67.945 0) (unit 1)
    (in_bom yes) (on_board yes) (dnp no) (fields_autoplaced)
    (property "Reference" "#PWR0314" (at 221.615 74.295 0)
      (effects (font (size 1.27 1.27)) hide)
    )
    (property "Value" "GND" (at 221.615 73.025 0)
      (effects (font (size 1.27 1.27)))
    )
    (property "Footprint" "" (at 230.505 75.565 0)
      (effects (font (size 1.27 1.27) (thickness 0.15)) (justify left bottom) hide)
    )
    (property "Datasheet" "" (at 230.505 80.645 0)
      (effects (font (size 1.27 1.27) (thickness 0.15)) (justify left bottom) hide)
    )
    (property "Author" "Antmicro" (at 230.505 75.565 0)
      (effects (font (size 1.27 1.27) (thickness 0.15)) (justify left bottom) hide)
    )
    (property "License" "Apache-2.0" (at 230.505 78.105 0)
      (effects (font (size 1.27 1.27) (thickness 0.15)) (justify left bottom) hide)
    )
    (pin "1")
    (instances
      (project "kria-k26-devboard"
        (path ""
          (reference "#PWR0314") (unit 1)
        )
      )
    )
  )

  (symbol (lib_id "kria-k26-devboard:GND") (at 229.235 67.945 0) (unit 1)
    (in_bom yes) (on_board yes) (dnp no) (fields_autoplaced)
    (property "Reference" "#PWR0315" (at 229.235 74.295 0)
      (effects (font (size 1.27 1.27)) hide)
    )
    (property "Value" "GND" (at 229.235 73.025 0)
      (effects (font (size 1.27 1.27)))
    )
    (property "Footprint" "" (at 238.125 75.565 0)
      (effects (font (size 1.27 1.27) (thickness 0.15)) (justify left bottom) hide)
    )
    (property "Datasheet" "" (at 238.125 80.645 0)
      (effects (font (size 1.27 1.27) (thickness 0.15)) (justify left bottom) hide)
    )
    (property "Author" "Antmicro" (at 238.125 75.565 0)
      (effects (font (size 1.27 1.27) (thickness 0.15)) (justify left bottom) hide)
    )
    (property "License" "Apache-2.0" (at 238.125 78.105 0)
      (effects (font (size 1.27 1.27) (thickness 0.15)) (justify left bottom) hide)
    )
    (pin "1")
    (instances
      (project "kria-k26-devboard"
        (path ""
          (reference "#PWR0315") (unit 1)
        )
      )
    )
  )

  (symbol (lib_id "kria-k26-devboard:GND") (at 236.855 67.945 0) (unit 1)
    (in_bom yes) (on_board yes) (dnp no) (fields_autoplaced)
    (property "Reference" "#PWR0316" (at 236.855 74.295 0)
      (effects (font (size 1.27 1.27)) hide)
    )
    (property "Value" "GND" (at 236.855 73.025 0)
      (effects (font (size 1.27 1.27)))
    )
    (property "Footprint" "" (at 245.745 75.565 0)
      (effects (font (size 1.27 1.27) (thickness 0.15)) (justify left bottom) hide)
    )
    (property "Datasheet" "" (at 245.745 80.645 0)
      (effects (font (size 1.27 1.27) (thickness 0.15)) (justify left bottom) hide)
    )
    (property "Author" "Antmicro" (at 245.745 75.565 0)
      (effects (font (size 1.27 1.27) (thickness 0.15)) (justify left bottom) hide)
    )
    (property "License" "Apache-2.0" (at 245.745 78.105 0)
      (effects (font (size 1.27 1.27) (thickness 0.15)) (justify left bottom) hide)
    )
    (pin "1")
    (instances
      (project "kria-k26-devboard"
        (path ""
          (reference "#PWR0316") (unit 1)
        )
      )
    )
  )

  (symbol (lib_id "kria-k26-devboard:GND") (at 226.06 120.65 0) (unit 1)
    (in_bom yes) (on_board yes) (dnp no) (fields_autoplaced)
    (property "Reference" "#PWR0313" (at 226.06 127 0)
      (effects (font (size 1.27 1.27)) hide)
    )
    (property "Value" "GND" (at 226.06 125.73 0)
      (effects (font (size 1.27 1.27)))
    )
    (property "Footprint" "" (at 234.95 128.27 0)
      (effects (font (size 1.27 1.27) (thickness 0.15)) (justify left bottom) hide)
    )
    (property "Datasheet" "" (at 234.95 133.35 0)
      (effects (font (size 1.27 1.27) (thickness 0.15)) (justify left bottom) hide)
    )
    (property "Author" "Antmicro" (at 234.95 128.27 0)
      (effects (font (size 1.27 1.27) (thickness 0.15)) (justify left bottom) hide)
    )
    (property "License" "Apache-2.0" (at 234.95 130.81 0)
      (effects (font (size 1.27 1.27) (thickness 0.15)) (justify left bottom) hide)
    )
    (pin "1")
    (instances
      (project "kria-k26-devboard"
        (path ""
          (reference "#PWR0313") (unit 1)
        )
      )
    )
  )

  (symbol (lib_id "kria-k26-devboard:SN74LVC1G125_SOT") (at 203.2 196.85 0) (unit 1)
    (in_bom yes) (on_board yes) (dnp no)
    (property "Reference" "U35" (at 212.09 189.865 0)
      (effects (font (size 1.524 1.524)))
    )
    (property "Value" "SN74LVC1G125_SOT" (at 212.09 191.77 0)
      (effects (font (size 1.27 1.27) (thickness 0.15)) (justify left bottom))
    )
    (property "Footprint" "kria-k26-devboard-footprints:SOT-753" (at 208.28 191.77 0)
      (effects (font (size 1.27 1.27) (thickness 0.15)) (justify left bottom) hide)
    )
    (property "Datasheet" "http://www.ti.com/general/docs/suppproductinfo.tsp?distId=10&gotoUrl=http%3A%2F%2Fwww.ti.com%2Flit%2Fgpn%2Fsn74lvc1g125" (at 208.28 189.23 0)
      (effects (font (size 1.27 1.27) (thickness 0.15)) (justify left bottom) hide)
    )
    (property "MPN" "SN74LVC1G125DBVR" (at 212.09 192.405 0)
      (effects (font (size 1.27 1.27) (thickness 0.15)) (justify left bottom) hide)
    )
    (property "Manufacturer" "Texas Instruments" (at 208.28 168.91 0)
      (effects (font (size 1.27 1.27) (thickness 0.15)) (justify left bottom) hide)
    )
    (property "Author" "Antmicro" (at 234.95 217.17 0)
      (effects (font (size 1.27 1.27) (thickness 0.15)) (justify left bottom) hide)
    )
    (property "License" "Apache-2.0" (at 234.95 219.71 0)
      (effects (font (size 1.27 1.27) (thickness 0.15)) (justify left bottom) hide)
    )
    (pin "1")
    (pin "2")
    (pin "3")
    (pin "4")
    (pin "5")
    (instances
      (project "kria-k26-devboard"
        (path ""
          (reference "U35") (unit 1)
        )
      )
    )
  )

  (symbol (lib_id "kria-k26-devboard:R_0R_0402") (at 194.945 259.08 0) (unit 1)
    (in_bom no) (on_board yes) (dnp yes)
    (property "Reference" "R86" (at 197.485 254 0)
      (effects (font (size 1.524 1.524)))
    )
    (property "Value" "R_0R_0402" (at 194.945 262.89 0)
      (effects (font (size 1.27 1.27) (thickness 0.15)) (justify left bottom) hide)
    )
    (property "Footprint" "kria-k26-devboard-footprints:R_0402_1005Metric" (at 200.025 254 0)
      (effects (font (size 1.27 1.27) (thickness 0.15)) (justify left bottom) hide)
    )
    (property "Datasheet" "https://industrial.panasonic.com/cdbs/www-data/pdf/RDA0000/AOA0000C301.pdf" (at 194.945 259.08 0)
      (effects (font (size 1.27 1.27) (thickness 0.15)) (justify left bottom) hide)
    )
    (property "Manufacturer" "Panasonic" (at 200.025 248.92 0)
      (effects (font (size 1.27 1.27) (thickness 0.15)) (justify left bottom) hide)
    )
    (property "MPN" "ERJ2GE0R00X" (at 200.025 251.46 0)
      (effects (font (size 1.27 1.27) (thickness 0.15)) (justify left bottom) hide)
    )
    (property "Val" "0R" (at 197.485 256.54 0)
      (effects (font (size 1.27 1.27) (thickness 0.15)))
    )
    (property "DNP" "DNP" (at 197.485 259.08 0)
      (effects (font (size 1.27 1.27)))
    )
    (property "License" "Apache-2.0" (at 215.265 284.48 0)
      (effects (font (size 1.27 1.27) (thickness 0.15)) (justify left bottom) hide)
    )
    (property "Author" "Antmicro" (at 215.265 287.02 0)
      (effects (font (size 1.27 1.27) (thickness 0.15)) (justify left bottom) hide)
    )
    (property "Tolerance" "~" (at 215.265 269.24 0)
      (effects (font (size 1.27 1.27)) (justify left bottom) hide)
    )
    (property "Current" "1A" (at 215.265 289.56 0)
      (effects (font (size 1.27 1.27) (thickness 0.15)) (justify left bottom) hide)
    )
    (pin "1")
    (pin "2")
    (instances
      (project "kria-k26-devboard"
        (path ""
          (reference "R86") (unit 1)
        )
      )
    )
  )

  (symbol (lib_id "kria-k26-devboard:GND") (at 364.49 158.115 0) (unit 1)
    (in_bom yes) (on_board yes) (dnp no)
    (property "Reference" "#PWR0318" (at 364.49 164.465 0)
      (effects (font (size 1.27 1.27)) hide)
    )
    (property "Value" "GND" (at 364.49 162.56 0)
      (effects (font (size 1.27 1.27)))
    )
    (property "Footprint" "" (at 373.38 165.735 0)
      (effects (font (size 1.27 1.27) (thickness 0.15)) (justify left bottom) hide)
    )
    (property "Datasheet" "" (at 373.38 170.815 0)
      (effects (font (size 1.27 1.27) (thickness 0.15)) (justify left bottom) hide)
    )
    (property "Author" "Antmicro" (at 373.38 165.735 0)
      (effects (font (size 1.27 1.27) (thickness 0.15)) (justify left bottom) hide)
    )
    (property "License" "Apache-2.0" (at 373.38 168.275 0)
      (effects (font (size 1.27 1.27) (thickness 0.15)) (justify left bottom) hide)
    )
    (pin "1")
    (instances
      (project "kria-k26-devboard"
        (path ""
          (reference "#PWR0318") (unit 1)
        )
      )
    )
  )

  (symbol (lib_id "kria-k26-devboard:R_1k_0402") (at 111.76 141.605 90) (unit 1)
    (in_bom yes) (on_board yes) (dnp no) (fields_autoplaced)
    (property "Reference" "R85" (at 109.22 137.795 90)
      (effects (font (size 1.524 1.524)) (justify left))
    )
    (property "Value" "R_1k_0402" (at 115.57 141.605 0)
      (effects (font (size 1.27 1.27) (thickness 0.15)) (justify left bottom) hide)
    )
    (property "Footprint" "kria-k26-devboard-footprints:R_0402_1005Metric" (at 106.68 136.525 0)
      (effects (font (size 1.27 1.27) (thickness 0.15)) (justify left bottom) hide)
    )
    (property "Datasheet" "https://www.bourns.com/docs/product-datasheets/cr.pdf" (at 111.76 141.605 0)
      (effects (font (size 1.27 1.27) (thickness 0.15)) (justify left bottom) hide)
    )
    (property "Manufacturer" "Bourns" (at 101.6 136.525 0)
      (effects (font (size 1.27 1.27) (thickness 0.15)) (justify left bottom) hide)
    )
    (property "MPN" "CR0402-FX-1001GLF" (at 104.14 136.525 0)
      (effects (font (size 1.27 1.27) (thickness 0.15)) (justify left bottom) hide)
    )
    (property "Val" "1k" (at 109.22 140.9699 90)
      (effects (font (size 1.27 1.27) (thickness 0.15)) (justify left))
    )
    (property "License" "Apache-2.0" (at 137.16 121.285 0)
      (effects (font (size 1.27 1.27) (thickness 0.15)) (justify left bottom) hide)
    )
    (property "Author" "Antmicro" (at 139.7 121.285 0)
      (effects (font (size 1.27 1.27) (thickness 0.15)) (justify left bottom) hide)
    )
    (property "Tolerance" "1%" (at 121.92 121.285 0)
      (effects (font (size 1.27 1.27)) (justify left bottom) hide)
    )
    (pin "1")
    (pin "2")
    (instances
      (project "kria-k26-devboard"
        (path ""
          (reference "R85") (unit 1)
        )
      )
    )
  )

  (symbol (lib_id "kria-k26-devboard:74LCX07_QFN") (at 293.37 125.73 0) (unit 6)
    (in_bom yes) (on_board yes) (dnp no) (fields_autoplaced)
    (property "Reference" "U36" (at 298.45 118.11 0)
      (effects (font (size 1.27 1.27)))
    )
    (property "Value" "74LCX07_QFN" (at 298.45 133.35 0)
      (effects (font (size 1.27 1.27) (thickness 0.15)) (justify left bottom))
    )
    (property "Footprint" "kria-k26-devboard-footprints:QFN-14-1EP_2.5x3mm_EP1.15x1.65mm_ONSemi_MLP14A" (at 295.91 134.62 0)
      (effects (font (size 1.27 1.27) (thickness 0.15)) (justify left bottom) hide)
    )
    (property "Datasheet" "https://www.mouser.com/datasheet/2/308/74LCX07_D-2309542.pdf" (at 293.37 125.73 0)
      (effects (font (size 1.27 1.27) (thickness 0.15)) (justify left bottom) hide)
    )
    (property "Manufacturer" "ON Semiconductor" (at 284.48 129.54 0)
      (effects (font (size 1.27 1.27) (thickness 0.15)) (justify left bottom) hide)
    )
    (property "MPN" "74LCX07BQX" (at 298.45 120.65 0)
      (effects (font (size 1.27 1.27) (thickness 0.15)) (justify left bottom) hide)
    )
    (property "Author" "Antmicro" (at 318.77 143.51 0)
      (effects (font (size 1.27 1.27) (thickness 0.15)) (justify left bottom) hide)
    )
    (property "License" "Apache-2.0" (at 318.77 146.05 0)
      (effects (font (size 1.27 1.27) (thickness 0.15)) (justify left bottom) hide)
    )
    (pin "12")
    (pin "13")
    (pin "1")
    (pin "2")
    (pin "3")
    (pin "4")
    (pin "5")
    (pin "6")
    (pin "8")
    (pin "9")
    (pin "10")
    (pin "11")
    (pin "14")
    (pin "15")
    (pin "7")
    (instances
      (project "kria-k26-devboard"
        (path ""
          (reference "U36") (unit 6)
        )
      )
    )
  )

  (symbol (lib_id "kria-k26-devboard:GND") (at 292.735 144.145 0) (unit 1)
    (in_bom yes) (on_board yes) (dnp no) (fields_autoplaced)
    (property "Reference" "#PWR0211" (at 292.735 150.495 0)
      (effects (font (size 1.27 1.27)) hide)
    )
    (property "Value" "GND" (at 292.735 149.225 0)
      (effects (font (size 1.27 1.27)))
    )
    (property "Footprint" "" (at 301.625 151.765 0)
      (effects (font (size 1.27 1.27) (thickness 0.15)) (justify left bottom) hide)
    )
    (property "Datasheet" "" (at 301.625 156.845 0)
      (effects (font (size 1.27 1.27) (thickness 0.15)) (justify left bottom) hide)
    )
    (property "Author" "Antmicro" (at 301.625 151.765 0)
      (effects (font (size 1.27 1.27) (thickness 0.15)) (justify left bottom) hide)
    )
    (property "License" "Apache-2.0" (at 301.625 154.305 0)
      (effects (font (size 1.27 1.27) (thickness 0.15)) (justify left bottom) hide)
    )
    (pin "1")
    (instances
      (project "kria-k26-devboard"
        (path ""
          (reference "#PWR0211") (unit 1)
        )
      )
    )
  )
)
